G04*
G04 #@! TF.GenerationSoftware,Altium Limited,Altium Designer,23.0.1 (38)*
G04*
G04 Layer_Color=8388736*
%FSLAX25Y25*%
%MOIN*%
G70*
G04*
G04 #@! TF.SameCoordinates,C48E81DB-6E20-4E2D-80E6-7C5AFAA1A21F*
G04*
G04*
G04 #@! TF.FilePolarity,Negative*
G04*
G01*
G75*
%ADD12C,0.02000*%
%ADD28C,0.02500*%
%ADD36R,0.01968X0.01870*%
%ADD38R,0.07835X0.09173*%
%ADD39R,0.09500X0.13500*%
%ADD43R,0.02631X0.02648*%
%ADD44R,0.03150X0.03150*%
%ADD48R,0.04724X0.01772*%
G04:AMPARAMS|DCode=49|XSize=33.06mil|YSize=8.76mil|CornerRadius=4.38mil|HoleSize=0mil|Usage=FLASHONLY|Rotation=90.000|XOffset=0mil|YOffset=0mil|HoleType=Round|Shape=RoundedRectangle|*
%AMROUNDEDRECTD49*
21,1,0.03306,0.00000,0,0,90.0*
21,1,0.02430,0.00876,0,0,90.0*
1,1,0.00876,0.00000,0.01215*
1,1,0.00876,0.00000,-0.01215*
1,1,0.00876,0.00000,-0.01215*
1,1,0.00876,0.00000,0.01215*
%
%ADD49ROUNDEDRECTD49*%
%ADD50R,0.00876X0.03306*%
%ADD51R,0.04166X0.05142*%
%ADD53R,0.02029X0.01860*%
%ADD54R,0.02288X0.02016*%
%ADD55R,0.01968X0.01968*%
%ADD56R,0.01968X0.01968*%
%ADD57R,0.02016X0.02288*%
%ADD58R,0.02992X0.04921*%
%ADD59R,0.03150X0.03150*%
%ADD60R,0.02648X0.02631*%
%ADD62R,0.09173X0.07835*%
%ADD63R,0.02648X0.02816*%
%ADD65R,0.02323X0.01772*%
%ADD66R,0.02756X0.02756*%
%ADD69R,0.11142X0.08661*%
%ADD70R,0.02816X0.02648*%
%ADD73R,0.03543X0.03150*%
%ADD74R,0.03150X0.03543*%
%ADD76R,0.05315X0.04331*%
%ADD77R,0.02648X0.02911*%
G04:AMPARAMS|DCode=78|XSize=61.02mil|YSize=23.62mil|CornerRadius=2.01mil|HoleSize=0mil|Usage=FLASHONLY|Rotation=180.000|XOffset=0mil|YOffset=0mil|HoleType=Round|Shape=RoundedRectangle|*
%AMROUNDEDRECTD78*
21,1,0.06102,0.01961,0,0,180.0*
21,1,0.05701,0.02362,0,0,180.0*
1,1,0.00402,-0.02850,0.00980*
1,1,0.00402,0.02850,0.00980*
1,1,0.00402,0.02850,-0.00980*
1,1,0.00402,-0.02850,-0.00980*
%
%ADD78ROUNDEDRECTD78*%
%ADD80R,0.06717X0.04546*%
%ADD84R,0.12362X0.06063*%
%ADD85R,0.09449X0.12992*%
%ADD87R,0.02911X0.02648*%
%ADD89R,0.01860X0.02029*%
%ADD90R,0.04331X0.05315*%
%ADD91R,0.02756X0.02756*%
G04:AMPARAMS|DCode=93|XSize=61.02mil|YSize=23.62mil|CornerRadius=2.01mil|HoleSize=0mil|Usage=FLASHONLY|Rotation=270.000|XOffset=0mil|YOffset=0mil|HoleType=Round|Shape=RoundedRectangle|*
%AMROUNDEDRECTD93*
21,1,0.06102,0.01961,0,0,270.0*
21,1,0.05701,0.02362,0,0,270.0*
1,1,0.00402,-0.00980,-0.02850*
1,1,0.00402,-0.00980,0.02850*
1,1,0.00402,0.00980,0.02850*
1,1,0.00402,0.00980,-0.02850*
%
%ADD93ROUNDEDRECTD93*%
%ADD96R,0.04921X0.03937*%
%ADD97R,0.03937X0.04921*%
%ADD105R,0.06063X0.12362*%
%ADD119R,0.03543X0.03150*%
%ADD120R,0.03543X0.02953*%
%ADD133R,0.01968X0.01378*%
G04:AMPARAMS|DCode=134|XSize=40.88mil|YSize=20.95mil|CornerRadius=10.48mil|HoleSize=0mil|Usage=FLASHONLY|Rotation=270.000|XOffset=0mil|YOffset=0mil|HoleType=Round|Shape=RoundedRectangle|*
%AMROUNDEDRECTD134*
21,1,0.04088,0.00000,0,0,270.0*
21,1,0.01993,0.02095,0,0,270.0*
1,1,0.02095,0.00000,-0.00996*
1,1,0.02095,0.00000,0.00996*
1,1,0.02095,0.00000,0.00996*
1,1,0.02095,0.00000,-0.00996*
%
%ADD134ROUNDEDRECTD134*%
%ADD135R,0.02095X0.04088*%
%ADD136R,0.02067X0.01181*%
%ADD137R,0.02067X0.01181*%
%ADD138R,0.02067X0.01181*%
%ADD139R,0.02067X0.01181*%
%ADD140R,0.01575X0.02067*%
%ADD141R,0.01575X0.02067*%
%ADD142R,0.01575X0.02067*%
%ADD143R,0.01575X0.02067*%
%ADD144R,0.31496X0.13583*%
%ADD145R,1.35433X0.23032*%
%ADD146R,0.05131X0.04934*%
%ADD147R,0.02572X0.02572*%
%ADD148R,0.02847X0.03005*%
%ADD149R,0.02965X0.02965*%
%ADD150R,0.02572X0.02769*%
%ADD151R,0.02769X0.02572*%
%ADD152R,0.04540X0.04540*%
%ADD153R,0.03162X0.03950*%
%ADD154R,0.04934X0.05131*%
G04:AMPARAMS|DCode=155|XSize=43.31mil|YSize=139.76mil|CornerRadius=21.65mil|HoleSize=0mil|Usage=FLASHONLY|Rotation=90.000|XOffset=0mil|YOffset=0mil|HoleType=Round|Shape=RoundedRectangle|*
%AMROUNDEDRECTD155*
21,1,0.04331,0.09646,0,0,90.0*
21,1,0.00000,0.13976,0,0,90.0*
1,1,0.04331,0.04823,0.00000*
1,1,0.04331,0.04823,0.00000*
1,1,0.04331,-0.04823,0.00000*
1,1,0.04331,-0.04823,0.00000*
%
%ADD155ROUNDEDRECTD155*%
%ADD156R,0.10039X0.06496*%
%ADD157R,0.02965X0.02965*%
%ADD158R,0.02362X0.00787*%
%ADD159R,0.00787X0.02362*%
%ADD160C,0.00709*%
%ADD161R,0.00787X0.02362*%
%ADD162R,0.02362X0.00787*%
%ADD163R,0.03359X0.03162*%
%ADD164R,0.08083X0.06706*%
%ADD165R,0.02965X0.03359*%
%ADD166R,0.11942X0.04343*%
%ADD167R,0.01575X0.01181*%
%ADD168R,0.01181X0.01575*%
%ADD169R,0.06299X0.14567*%
%ADD170R,0.03359X0.02965*%
%ADD171R,0.02769X0.02965*%
%ADD172R,0.03556X0.03359*%
%ADD173R,0.02572X0.02572*%
%ADD174R,0.02965X0.03162*%
%ADD175R,0.03320X0.03477*%
%ADD176R,0.03359X0.03556*%
%ADD177R,0.06706X0.08083*%
%ADD178R,0.03162X0.02965*%
%ADD179R,0.03477X0.03320*%
%ADD180R,0.09087X0.05209*%
%ADD181R,0.06115X0.07493*%
%ADD182R,0.01784X0.06902*%
%ADD183R,0.07493X0.06115*%
%ADD184R,0.06902X0.01784*%
%ADD185R,0.07887X0.01784*%
%ADD186R,0.06509X0.08280*%
%ADD187R,0.05800X0.20800*%
%ADD188R,0.04540X0.06509*%
%ADD189R,0.06509X0.04540*%
%ADD190R,0.04343X0.02769*%
%ADD191R,0.02769X0.04343*%
%ADD192R,0.06509X0.05328*%
%ADD193R,0.04147X0.01981*%
%ADD194R,0.04540X0.03950*%
%ADD195R,0.04343X0.01824*%
%ADD196R,0.01824X0.04343*%
%ADD197R,0.13595X0.13595*%
%ADD198R,0.04343X0.03162*%
%ADD199R,0.02965X0.03162*%
%ADD200R,0.09461X0.04934*%
%ADD201R,0.04934X0.04737*%
%ADD202R,0.04540X0.04540*%
%ADD203R,0.03556X0.04343*%
%ADD204R,0.03753X0.04147*%
%ADD205R,0.06312X0.06312*%
%ADD206R,0.04737X0.06312*%
%ADD207R,0.03600X0.17300*%
%ADD208R,0.03600X0.13400*%
%ADD209O,0.09461X0.03162*%
%ADD210O,0.08280X0.03162*%
%ADD211R,0.03635X0.04737*%
G04:AMPARAMS|DCode=212|XSize=43.31mil|YSize=70.87mil|CornerRadius=21.65mil|HoleSize=0mil|Usage=FLASHONLY|Rotation=90.000|XOffset=0mil|YOffset=0mil|HoleType=Round|Shape=RoundedRectangle|*
%AMROUNDEDRECTD212*
21,1,0.04331,0.02756,0,0,90.0*
21,1,0.00000,0.07087,0,0,90.0*
1,1,0.04331,0.01378,0.00000*
1,1,0.04331,0.01378,0.00000*
1,1,0.04331,-0.01378,0.00000*
1,1,0.04331,-0.01378,0.00000*
%
%ADD212ROUNDEDRECTD212*%
G04:AMPARAMS|DCode=213|XSize=47.24mil|YSize=62.99mil|CornerRadius=23.62mil|HoleSize=0mil|Usage=FLASHONLY|Rotation=90.000|XOffset=0mil|YOffset=0mil|HoleType=Round|Shape=RoundedRectangle|*
%AMROUNDEDRECTD213*
21,1,0.04724,0.01575,0,0,90.0*
21,1,0.00000,0.06299,0,0,90.0*
1,1,0.04724,0.00787,0.00000*
1,1,0.04724,0.00787,0.00000*
1,1,0.04724,-0.00787,0.00000*
1,1,0.04724,-0.00787,0.00000*
%
%ADD213ROUNDEDRECTD213*%
%ADD214C,0.11800*%
%ADD215R,0.10827X0.10827*%
%ADD216C,0.10827*%
%ADD217C,0.00800*%
%ADD218R,0.06902X0.06902*%
%ADD219C,0.06902*%
%ADD220C,0.10800*%
%ADD221C,0.02966*%
%ADD222C,0.24800*%
%ADD223R,0.00800X0.00800*%
%ADD224C,0.07398*%
%ADD225C,0.09461*%
%ADD226R,0.08674X0.08674*%
%ADD227R,0.06706X0.06706*%
%ADD228C,0.06706*%
%ADD229C,0.25800*%
%ADD230C,0.02400*%
%ADD231C,0.05800*%
%ADD232C,0.20800*%
%ADD233C,0.02769*%
G36*
X615748Y-90551D02*
X613386D01*
Y-89764D01*
X615158D01*
Y-88976D01*
X615748D01*
Y-90551D01*
D02*
G37*
G36*
X582874D02*
X580512D01*
Y-89764D01*
X582283D01*
Y-88976D01*
X582874D01*
Y-90551D01*
D02*
G37*
G36*
X245669Y-125000D02*
X244882D01*
Y-123228D01*
X244094D01*
Y-122638D01*
X245669D01*
Y-125000D01*
D02*
G37*
G36*
X403972Y-325366D02*
X404024Y-325377D01*
X404073Y-325394D01*
X404077Y-325395D01*
X404242D01*
X404295Y-325399D01*
X404346Y-325409D01*
X404396Y-325426D01*
X404399Y-325428D01*
X404404D01*
X404456Y-325431D01*
X404507Y-325441D01*
X404557Y-325458D01*
X404565Y-325462D01*
X404585Y-325463D01*
X404636Y-325473D01*
X404686Y-325490D01*
X404733Y-325514D01*
X404743Y-325520D01*
X404751Y-325523D01*
X404771Y-325533D01*
X404798Y-325538D01*
X404847Y-325555D01*
X404894Y-325578D01*
X404904Y-325584D01*
X404912Y-325587D01*
X404932Y-325597D01*
X404959Y-325603D01*
X405009Y-325619D01*
X405056Y-325643D01*
X405099Y-325672D01*
X405110Y-325681D01*
X405123Y-325693D01*
X405153Y-325707D01*
X405162Y-325713D01*
X405170Y-325716D01*
X405217Y-325739D01*
X405261Y-325768D01*
X405285Y-325789D01*
X405314Y-325804D01*
X405358Y-325833D01*
X405381Y-325854D01*
X405411Y-325868D01*
X405454Y-325898D01*
X405494Y-325932D01*
X405509Y-325949D01*
X405526Y-325964D01*
X405541Y-325982D01*
X405558Y-325997D01*
X405573Y-326014D01*
X405590Y-326029D01*
X405606Y-326046D01*
X405623Y-326061D01*
X405638Y-326078D01*
X405655Y-326093D01*
X405670Y-326111D01*
X405687Y-326126D01*
X405702Y-326143D01*
X405720Y-326158D01*
X405735Y-326175D01*
X405752Y-326190D01*
X405767Y-326207D01*
X405776Y-326216D01*
X405784Y-326222D01*
X405799Y-326240D01*
X405816Y-326255D01*
X405831Y-326272D01*
X405841Y-326280D01*
X405849Y-326287D01*
X405883Y-326326D01*
X405912Y-326370D01*
X405927Y-326399D01*
X405948Y-326423D01*
X405977Y-326467D01*
X405991Y-326496D01*
X406012Y-326520D01*
X406041Y-326564D01*
X406065Y-326611D01*
X406067Y-326619D01*
X406074Y-326628D01*
X406088Y-326657D01*
X406109Y-326681D01*
X406138Y-326725D01*
X406161Y-326772D01*
X406164Y-326780D01*
X406170Y-326789D01*
X406193Y-326836D01*
X406210Y-326886D01*
X406216Y-326913D01*
X406226Y-326933D01*
X406228Y-326941D01*
X406235Y-326951D01*
X406258Y-326998D01*
X406275Y-327047D01*
X406280Y-327074D01*
X406290Y-327095D01*
X406307Y-327144D01*
X406317Y-327196D01*
X406319Y-327216D01*
Y-327216D01*
X406323Y-327224D01*
X406339Y-327273D01*
X406350Y-327325D01*
X406351Y-327345D01*
X406355Y-327353D01*
X406372Y-327402D01*
X406382Y-327454D01*
X406385Y-327506D01*
Y-327538D01*
Y-327571D01*
Y-327603D01*
Y-327635D01*
Y-327667D01*
Y-327672D01*
X406387Y-327675D01*
X406404Y-327725D01*
X406414Y-327776D01*
X406418Y-327829D01*
Y-327861D01*
Y-327893D01*
Y-327925D01*
Y-327958D01*
X406414Y-328010D01*
X406404Y-328061D01*
X406387Y-328111D01*
X406385Y-328115D01*
Y-328119D01*
Y-328151D01*
Y-328184D01*
Y-328216D01*
Y-328248D01*
X406382Y-328300D01*
X406372Y-328352D01*
X406355Y-328401D01*
X406353Y-328405D01*
Y-328409D01*
X406350Y-328462D01*
X406339Y-328513D01*
X406323Y-328563D01*
X406313Y-328583D01*
X406307Y-328610D01*
X406290Y-328660D01*
X406280Y-328680D01*
X406275Y-328707D01*
X406258Y-328756D01*
X406248Y-328777D01*
X406243Y-328803D01*
X406226Y-328853D01*
X406203Y-328900D01*
X406196Y-328910D01*
X406193Y-328918D01*
X406170Y-328965D01*
X406164Y-328974D01*
X406161Y-328982D01*
X406138Y-329029D01*
X406132Y-329039D01*
X406129Y-329047D01*
X406106Y-329094D01*
X406100Y-329103D01*
X406097Y-329111D01*
X406074Y-329158D01*
X406067Y-329168D01*
X406065Y-329176D01*
X406041Y-329223D01*
X406012Y-329266D01*
X405991Y-329290D01*
X405977Y-329320D01*
X405948Y-329363D01*
X405913Y-329403D01*
X405896Y-329418D01*
X405894Y-329419D01*
X405880Y-329449D01*
X405851Y-329492D01*
X405816Y-329532D01*
X405799Y-329547D01*
X405784Y-329564D01*
X405767Y-329579D01*
X405752Y-329596D01*
X405735Y-329611D01*
X405720Y-329628D01*
X405702Y-329643D01*
X405687Y-329661D01*
X405670Y-329676D01*
X405655Y-329693D01*
X405638Y-329708D01*
X405623Y-329725D01*
X405606Y-329740D01*
X405590Y-329757D01*
X405573Y-329772D01*
X405558Y-329790D01*
X405519Y-329824D01*
X405475Y-329853D01*
X405446Y-329868D01*
X405444Y-329869D01*
X405429Y-329887D01*
X405412Y-329902D01*
X405397Y-329919D01*
X405358Y-329953D01*
X405314Y-329982D01*
X405285Y-329997D01*
X405261Y-330018D01*
X405217Y-330047D01*
X405170Y-330070D01*
X405162Y-330073D01*
X405153Y-330079D01*
X405105Y-330102D01*
X405097Y-330105D01*
X405088Y-330112D01*
X405041Y-330135D01*
X405033Y-330137D01*
X405023Y-330144D01*
X404977Y-330167D01*
X404969Y-330170D01*
X404959Y-330176D01*
X404912Y-330199D01*
X404904Y-330202D01*
X404894Y-330208D01*
X404847Y-330231D01*
X404798Y-330248D01*
X404771Y-330254D01*
X404751Y-330264D01*
X404701Y-330281D01*
X404674Y-330286D01*
X404654Y-330296D01*
X404604Y-330313D01*
X404553Y-330323D01*
X404533Y-330324D01*
X404525Y-330328D01*
X404475Y-330345D01*
X404424Y-330355D01*
X404371Y-330359D01*
X404367D01*
X404363Y-330361D01*
X404314Y-330377D01*
X404262Y-330388D01*
X404210Y-330391D01*
X401081D01*
X401028Y-330388D01*
X400977Y-330377D01*
X400927Y-330361D01*
X400924Y-330359D01*
X400919D01*
X400867Y-330355D01*
X400816Y-330345D01*
X400766Y-330328D01*
X400745Y-330318D01*
X400719Y-330313D01*
X400669Y-330296D01*
X400649Y-330286D01*
X400649D01*
X400622Y-330281D01*
X400572Y-330264D01*
X400552Y-330254D01*
X400525Y-330248D01*
X400476Y-330231D01*
X400429Y-330208D01*
X400419Y-330202D01*
X400411Y-330199D01*
X400391Y-330189D01*
X400364Y-330184D01*
X400314Y-330167D01*
X400267Y-330144D01*
X400224Y-330115D01*
X400200Y-330094D01*
X400171Y-330079D01*
X400161Y-330073D01*
X400153Y-330070D01*
X400106Y-330047D01*
X400062Y-330018D01*
X400038Y-329997D01*
X400009Y-329982D01*
X399966Y-329953D01*
X399942Y-329932D01*
X399912Y-329918D01*
X399869Y-329889D01*
X399829Y-329854D01*
X399829Y-329853D01*
X399814Y-329837D01*
X399797Y-329822D01*
X399782Y-329805D01*
X399765Y-329790D01*
X399750Y-329772D01*
X399733Y-329757D01*
X399717Y-329740D01*
X399700Y-329725D01*
X399685Y-329708D01*
X399668Y-329693D01*
X399653Y-329676D01*
X399636Y-329661D01*
X399621Y-329643D01*
X399604Y-329628D01*
X399588Y-329611D01*
X399571Y-329596D01*
X399556Y-329579D01*
X399539Y-329564D01*
X399524Y-329547D01*
X399507Y-329532D01*
X399492Y-329514D01*
X399475Y-329499D01*
X399440Y-329460D01*
X399411Y-329416D01*
X399396Y-329387D01*
X399395Y-329385D01*
X399378Y-329370D01*
X399343Y-329331D01*
X399314Y-329287D01*
X399291Y-329240D01*
X399288Y-329232D01*
X399282Y-329223D01*
X399267Y-329193D01*
X399246Y-329170D01*
X399217Y-329126D01*
X399194Y-329079D01*
X399191Y-329071D01*
X399185Y-329061D01*
X399162Y-329014D01*
X399159Y-329006D01*
X399153Y-328997D01*
X399130Y-328950D01*
X399127Y-328942D01*
X399120Y-328932D01*
X399097Y-328885D01*
X399080Y-328836D01*
X399075Y-328809D01*
X399065Y-328789D01*
X399048Y-328739D01*
X399043Y-328712D01*
X399033Y-328692D01*
X399016Y-328642D01*
X399011Y-328615D01*
X399001Y-328595D01*
X398984Y-328545D01*
X398973Y-328494D01*
X398970Y-328442D01*
Y-328437D01*
X398968Y-328434D01*
X398951Y-328384D01*
X398941Y-328333D01*
X398938Y-328280D01*
Y-328276D01*
X398936Y-328272D01*
X398919Y-328223D01*
X398909Y-328171D01*
X398905Y-328119D01*
Y-328087D01*
Y-328054D01*
Y-328022D01*
Y-327990D01*
Y-327958D01*
Y-327925D01*
Y-327893D01*
Y-327861D01*
Y-327829D01*
Y-327796D01*
Y-327764D01*
Y-327732D01*
Y-327700D01*
X398909Y-327647D01*
X398919Y-327596D01*
X398936Y-327546D01*
X398938Y-327543D01*
Y-327538D01*
Y-327506D01*
Y-327474D01*
X398941Y-327421D01*
X398951Y-327370D01*
X398968Y-327320D01*
X398972Y-327312D01*
X398973Y-327292D01*
X398984Y-327241D01*
X399001Y-327191D01*
X399004Y-327184D01*
X399006Y-327163D01*
X399016Y-327112D01*
X399033Y-327062D01*
X399056Y-327015D01*
X399062Y-327006D01*
X399065Y-326998D01*
X399075Y-326977D01*
X399080Y-326951D01*
X399097Y-326901D01*
X399120Y-326854D01*
X399127Y-326845D01*
X399130Y-326836D01*
X399153Y-326789D01*
X399159Y-326780D01*
X399162Y-326772D01*
X399185Y-326725D01*
X399191Y-326715D01*
X399194Y-326707D01*
X399217Y-326660D01*
X399219Y-326657D01*
X399224Y-326651D01*
X399226Y-326643D01*
X399250Y-326596D01*
X399279Y-326552D01*
X399300Y-326528D01*
X399314Y-326499D01*
X399343Y-326455D01*
X399364Y-326432D01*
X399378Y-326402D01*
X399408Y-326359D01*
X399442Y-326319D01*
X399445Y-326317D01*
X399460Y-326304D01*
X399475Y-326287D01*
X399482Y-326280D01*
X399492Y-326272D01*
X399507Y-326255D01*
X399524Y-326240D01*
X399539Y-326222D01*
X399556Y-326207D01*
X399571Y-326190D01*
X399588Y-326175D01*
X399604Y-326158D01*
X399621Y-326143D01*
X399636Y-326126D01*
X399653Y-326111D01*
X399668Y-326093D01*
X399685Y-326078D01*
X399700Y-326061D01*
X399717Y-326046D01*
X399717Y-326046D01*
X399733Y-326029D01*
X399750Y-326014D01*
X399765Y-325997D01*
X399782Y-325982D01*
X399797Y-325964D01*
X399814Y-325949D01*
X399829Y-325932D01*
X399847Y-325917D01*
X399862Y-325900D01*
X399901Y-325865D01*
X399945Y-325836D01*
X399974Y-325822D01*
X399998Y-325801D01*
X400041Y-325772D01*
X400071Y-325757D01*
X400095Y-325736D01*
X400138Y-325707D01*
X400185Y-325684D01*
X400193Y-325681D01*
X400203Y-325675D01*
X400250Y-325652D01*
X400258Y-325649D01*
X400267Y-325643D01*
X400314Y-325619D01*
X400322Y-325617D01*
X400332Y-325610D01*
X400379Y-325587D01*
X400428Y-325570D01*
X400455Y-325565D01*
X400476Y-325555D01*
X400484Y-325552D01*
X400493Y-325546D01*
X400540Y-325523D01*
X400590Y-325506D01*
X400616Y-325500D01*
X400637Y-325490D01*
X400687Y-325473D01*
X400738Y-325463D01*
X400758Y-325462D01*
X400766Y-325458D01*
X400816Y-325441D01*
X400867Y-325431D01*
X400887Y-325430D01*
X400895Y-325426D01*
X400945Y-325409D01*
X400996Y-325399D01*
X401048Y-325395D01*
X401246D01*
X401250Y-325394D01*
X401300Y-325377D01*
X401351Y-325366D01*
X401403Y-325363D01*
X403855D01*
X403871Y-325364D01*
X403888Y-325363D01*
X403920D01*
X403972Y-325366D01*
D02*
G37*
G36*
X322835Y-335974D02*
X123031D01*
Y-136171D01*
X322835D01*
Y-335974D01*
D02*
G37*
G36*
X411392Y-342207D02*
X411444Y-342217D01*
X411493Y-342234D01*
X411497Y-342236D01*
X411533D01*
X411586Y-342239D01*
X411637Y-342250D01*
X411687Y-342266D01*
X411695Y-342270D01*
X411715Y-342272D01*
X411766Y-342282D01*
X411816Y-342299D01*
X411836Y-342309D01*
X411863Y-342314D01*
X411913Y-342331D01*
X411933Y-342341D01*
X411960Y-342346D01*
X412009Y-342363D01*
X412057Y-342386D01*
X412066Y-342393D01*
X412074Y-342395D01*
X412094Y-342406D01*
X412121Y-342411D01*
X412171Y-342428D01*
X412218Y-342451D01*
X412227Y-342457D01*
X412235Y-342460D01*
X412282Y-342483D01*
X412326Y-342512D01*
X412350Y-342533D01*
X412379Y-342548D01*
X412389Y-342554D01*
X412397Y-342557D01*
X412444Y-342580D01*
X412487Y-342609D01*
X412511Y-342630D01*
X412540Y-342645D01*
X412584Y-342674D01*
X412624Y-342708D01*
X412639Y-342725D01*
X412656Y-342741D01*
X412671Y-342758D01*
X412672Y-342759D01*
X412702Y-342774D01*
X412745Y-342803D01*
X412785Y-342837D01*
X412800Y-342854D01*
X412817Y-342869D01*
X412832Y-342887D01*
X412849Y-342902D01*
X412864Y-342919D01*
X412882Y-342934D01*
X412897Y-342951D01*
X412914Y-342966D01*
X412929Y-342984D01*
X412946Y-342999D01*
X412961Y-343016D01*
X412978Y-343031D01*
X412993Y-343048D01*
X413011Y-343063D01*
X413045Y-343103D01*
X413074Y-343146D01*
X413089Y-343175D01*
X413090Y-343177D01*
X413107Y-343192D01*
X413142Y-343232D01*
X413171Y-343275D01*
X413186Y-343304D01*
X413206Y-343328D01*
X413236Y-343372D01*
X413259Y-343419D01*
X413262Y-343427D01*
X413268Y-343437D01*
X413282Y-343466D01*
X413303Y-343490D01*
X413332Y-343533D01*
X413356Y-343580D01*
X413358Y-343588D01*
X413365Y-343598D01*
X413388Y-343645D01*
X413405Y-343694D01*
X413408Y-343710D01*
X413410Y-343721D01*
X413420Y-343742D01*
X413423Y-343750D01*
X413429Y-343759D01*
X413452Y-343806D01*
X413469Y-343856D01*
X413475Y-343882D01*
X413485Y-343903D01*
X413502Y-343953D01*
X413507Y-343979D01*
X413509Y-343984D01*
X413517Y-344000D01*
X413534Y-344049D01*
X413544Y-344101D01*
X413545Y-344121D01*
X413549Y-344129D01*
X413566Y-344178D01*
X413576Y-344230D01*
X413580Y-344282D01*
Y-344314D01*
Y-344319D01*
X413582Y-344322D01*
X413598Y-344372D01*
X413609Y-344423D01*
X413612Y-344476D01*
Y-344508D01*
Y-344540D01*
Y-344572D01*
Y-344605D01*
Y-344637D01*
Y-344669D01*
Y-344702D01*
Y-344734D01*
Y-344766D01*
Y-344798D01*
Y-344831D01*
Y-344863D01*
Y-344895D01*
Y-344927D01*
Y-344960D01*
X413609Y-345012D01*
X413598Y-345063D01*
X413582Y-345113D01*
X413580Y-345117D01*
Y-345121D01*
Y-345153D01*
X413576Y-345205D01*
X413566Y-345257D01*
X413549Y-345307D01*
X413545Y-345314D01*
X413544Y-345335D01*
X413534Y-345386D01*
X413517Y-345436D01*
X413507Y-345456D01*
X413502Y-345483D01*
X413485Y-345532D01*
X413475Y-345553D01*
X413469Y-345580D01*
X413452Y-345629D01*
X413429Y-345676D01*
X413423Y-345686D01*
X413420Y-345694D01*
X413397Y-345741D01*
X413391Y-345750D01*
X413388Y-345758D01*
X413365Y-345805D01*
X413358Y-345815D01*
X413356Y-345823D01*
X413332Y-345870D01*
X413326Y-345879D01*
X413323Y-345887D01*
X413300Y-345934D01*
X413294Y-345944D01*
X413291Y-345952D01*
X413268Y-345999D01*
X413239Y-346042D01*
X413218Y-346066D01*
X413203Y-346096D01*
X413174Y-346139D01*
X413155Y-346161D01*
X413153Y-346163D01*
X413139Y-346192D01*
X413110Y-346236D01*
X413075Y-346275D01*
X413058Y-346290D01*
X413043Y-346308D01*
X413026Y-346323D01*
X413014Y-346337D01*
X413011Y-346340D01*
X412993Y-346355D01*
X412986Y-346364D01*
X412978Y-346372D01*
X412961Y-346387D01*
X412946Y-346405D01*
X412929Y-346420D01*
X412914Y-346437D01*
X412897Y-346452D01*
X412882Y-346469D01*
X412864Y-346484D01*
X412849Y-346501D01*
X412832Y-346516D01*
X412817Y-346534D01*
X412800Y-346549D01*
X412785Y-346566D01*
X412768Y-346581D01*
X412752Y-346598D01*
X412735Y-346613D01*
X412721Y-346630D01*
X412720Y-346630D01*
X412703Y-346645D01*
X412688Y-346663D01*
X412649Y-346697D01*
X412605Y-346726D01*
X412576Y-346741D01*
X412574Y-346742D01*
X412559Y-346759D01*
X412520Y-346794D01*
X412476Y-346823D01*
X412429Y-346846D01*
X412421Y-346849D01*
X412411Y-346855D01*
X412382Y-346870D01*
X412358Y-346891D01*
X412315Y-346920D01*
X412268Y-346943D01*
X412260Y-346946D01*
X412250Y-346952D01*
X412203Y-346975D01*
X412195Y-346978D01*
X412186Y-346984D01*
X412139Y-347008D01*
X412089Y-347024D01*
X412062Y-347030D01*
X412042Y-347040D01*
X412034Y-347043D01*
X412024Y-347049D01*
X411977Y-347072D01*
X411928Y-347089D01*
X411901Y-347094D01*
X411880Y-347104D01*
X411831Y-347121D01*
X411779Y-347131D01*
X411759Y-347133D01*
X411751Y-347137D01*
X411702Y-347153D01*
X411650Y-347164D01*
X411598Y-347167D01*
X411594D01*
X411590Y-347169D01*
X411541Y-347186D01*
X411489Y-347196D01*
X411437Y-347199D01*
X411400D01*
X411397Y-347201D01*
X411347Y-347218D01*
X411296Y-347228D01*
X411243Y-347232D01*
X411211D01*
X411195Y-347231D01*
X411179Y-347232D01*
X411146D01*
X411130Y-347231D01*
X411114Y-347232D01*
X410888D01*
X410836Y-347228D01*
X410784Y-347218D01*
X410735Y-347201D01*
X410731Y-347199D01*
X410662D01*
X410610Y-347196D01*
X410559Y-347186D01*
X410509Y-347169D01*
X410505Y-347167D01*
X410501D01*
X410449Y-347164D01*
X410397Y-347153D01*
X410348Y-347137D01*
X410327Y-347127D01*
X410301Y-347121D01*
X410251Y-347104D01*
X410230Y-347094D01*
X410204Y-347089D01*
X410154Y-347072D01*
X410134Y-347062D01*
X410107Y-347057D01*
X410057Y-347040D01*
X410010Y-347017D01*
X410001Y-347010D01*
X409993Y-347008D01*
X409946Y-346984D01*
X409936Y-346978D01*
X409928Y-346975D01*
X409881Y-346952D01*
X409872Y-346946D01*
X409864Y-346943D01*
X409817Y-346920D01*
X409807Y-346914D01*
X409799Y-346911D01*
X409752Y-346888D01*
X409709Y-346859D01*
X409685Y-346838D01*
X409656Y-346823D01*
X409612Y-346794D01*
X409588Y-346773D01*
X409559Y-346759D01*
X409515Y-346729D01*
X409476Y-346695D01*
X409461Y-346678D01*
X409443Y-346663D01*
X409428Y-346645D01*
X409427Y-346644D01*
X409397Y-346630D01*
X409354Y-346600D01*
X409314Y-346566D01*
X409299Y-346549D01*
X409282Y-346534D01*
X409267Y-346516D01*
X409250Y-346501D01*
X409235Y-346484D01*
X409218Y-346469D01*
X409202Y-346452D01*
X409185Y-346437D01*
X409170Y-346420D01*
X409153Y-346405D01*
X409119Y-346365D01*
X409089Y-346322D01*
X409075Y-346292D01*
X409073Y-346290D01*
X409056Y-346275D01*
X409041Y-346258D01*
X409024Y-346243D01*
X408989Y-346204D01*
X408960Y-346160D01*
X408946Y-346131D01*
X408931Y-346114D01*
X408925Y-346107D01*
X408896Y-346063D01*
X408873Y-346016D01*
X408870Y-346008D01*
X408863Y-345999D01*
X408849Y-345970D01*
X408828Y-345946D01*
X408799Y-345902D01*
X408776Y-345855D01*
X408773Y-345847D01*
X408767Y-345838D01*
X408743Y-345791D01*
X408741Y-345782D01*
X408735Y-345773D01*
X408711Y-345726D01*
X408694Y-345676D01*
X408689Y-345650D01*
X408679Y-345629D01*
X408676Y-345621D01*
X408670Y-345612D01*
X408647Y-345565D01*
X408630Y-345515D01*
X408625Y-345488D01*
X408614Y-345468D01*
X408598Y-345418D01*
X408587Y-345367D01*
X408587Y-345355D01*
X408586Y-345347D01*
X408582Y-345339D01*
X408565Y-345289D01*
X408555Y-345238D01*
X408552Y-345185D01*
Y-345181D01*
X408550Y-345178D01*
X408533Y-345128D01*
X408523Y-345076D01*
X408520Y-345024D01*
Y-344992D01*
Y-344960D01*
Y-344927D01*
Y-344895D01*
Y-344863D01*
Y-344831D01*
Y-344798D01*
Y-344766D01*
Y-344734D01*
Y-344702D01*
Y-344669D01*
Y-344637D01*
Y-344605D01*
Y-344572D01*
Y-344540D01*
Y-344508D01*
Y-344476D01*
Y-344443D01*
Y-344411D01*
X408523Y-344359D01*
X408533Y-344307D01*
X408550Y-344258D01*
X408552Y-344254D01*
Y-344250D01*
X408555Y-344198D01*
X408565Y-344146D01*
X408582Y-344096D01*
X408586Y-344089D01*
X408587Y-344069D01*
X408598Y-344017D01*
X408614Y-343967D01*
X408624Y-343947D01*
X408625Y-343947D01*
X408630Y-343920D01*
X408647Y-343871D01*
X408657Y-343850D01*
X408662Y-343824D01*
X408679Y-343774D01*
X408702Y-343727D01*
X408706Y-343721D01*
X408709Y-343717D01*
X408711Y-343709D01*
X408735Y-343662D01*
X408741Y-343653D01*
X408743Y-343645D01*
X408767Y-343598D01*
X408773Y-343588D01*
X408776Y-343580D01*
X408799Y-343533D01*
X408800Y-343531D01*
X408805Y-343524D01*
X408808Y-343516D01*
X408831Y-343469D01*
X408838Y-343459D01*
X408840Y-343451D01*
X408863Y-343404D01*
X408893Y-343361D01*
X408914Y-343337D01*
X408928Y-343307D01*
X408957Y-343264D01*
X408992Y-343224D01*
X409009Y-343209D01*
X409010Y-343208D01*
X409025Y-343178D01*
X409054Y-343135D01*
X409089Y-343095D01*
X409106Y-343080D01*
X409121Y-343063D01*
X409138Y-343048D01*
X409153Y-343031D01*
X409170Y-343016D01*
X409185Y-342999D01*
X409202Y-342984D01*
X409218Y-342966D01*
X409235Y-342951D01*
X409250Y-342934D01*
X409267Y-342919D01*
X409282Y-342902D01*
X409299Y-342887D01*
X409314Y-342869D01*
X409332Y-342854D01*
X409347Y-342837D01*
X409364Y-342822D01*
X409379Y-342805D01*
X409396Y-342790D01*
X409411Y-342773D01*
X409451Y-342738D01*
X409494Y-342709D01*
X409523Y-342695D01*
X409547Y-342674D01*
X409591Y-342645D01*
X409620Y-342630D01*
X409644Y-342609D01*
X409688Y-342580D01*
X409717Y-342565D01*
X409741Y-342545D01*
X409785Y-342515D01*
X409831Y-342492D01*
X409839Y-342490D01*
X409849Y-342483D01*
X409896Y-342460D01*
X409904Y-342457D01*
X409914Y-342451D01*
X409961Y-342428D01*
X409969Y-342425D01*
X409978Y-342419D01*
X410025Y-342395D01*
X410075Y-342379D01*
X410101Y-342373D01*
X410122Y-342363D01*
X410172Y-342346D01*
X410198Y-342341D01*
X410219Y-342331D01*
X410268Y-342314D01*
X410295Y-342309D01*
X410316Y-342299D01*
X410365Y-342282D01*
X410417Y-342272D01*
X410437Y-342270D01*
X410444Y-342266D01*
X410494Y-342250D01*
X410546Y-342239D01*
X410598Y-342236D01*
X410602D01*
X410606Y-342234D01*
X410655Y-342217D01*
X410707Y-342207D01*
X410759Y-342204D01*
X411340D01*
X411392Y-342207D01*
D02*
G37*
G36*
X394261Y-325366D02*
X394313Y-325377D01*
X394362Y-325394D01*
X394366Y-325395D01*
X394564D01*
X394616Y-325399D01*
X394668Y-325409D01*
X394717Y-325426D01*
X394725Y-325430D01*
X394745Y-325431D01*
X394797Y-325441D01*
X394846Y-325458D01*
X394854Y-325462D01*
X394874Y-325463D01*
X394926Y-325473D01*
X394975Y-325490D01*
X394996Y-325500D01*
X395022Y-325506D01*
X395072Y-325523D01*
X395093Y-325533D01*
X395119Y-325538D01*
X395169Y-325555D01*
X395216Y-325578D01*
X395225Y-325584D01*
X395233Y-325587D01*
X395280Y-325610D01*
X395290Y-325617D01*
X395298Y-325619D01*
X395345Y-325643D01*
X395355Y-325649D01*
X395362Y-325652D01*
X395409Y-325675D01*
X395419Y-325681D01*
X395427Y-325684D01*
X395474Y-325707D01*
X395483Y-325713D01*
X395492Y-325716D01*
X395538Y-325739D01*
X395582Y-325768D01*
X395606Y-325789D01*
X395635Y-325804D01*
X395679Y-325833D01*
X395718Y-325868D01*
X395733Y-325885D01*
X395735Y-325886D01*
X395764Y-325901D01*
X395808Y-325930D01*
X395847Y-325964D01*
X395863Y-325982D01*
X395872Y-325990D01*
X395880Y-325997D01*
X395895Y-326014D01*
X395912Y-326029D01*
X395927Y-326046D01*
X395936Y-326054D01*
X395944Y-326061D01*
X395959Y-326078D01*
X395976Y-326093D01*
X395991Y-326111D01*
X396009Y-326126D01*
X396024Y-326143D01*
X396038Y-326156D01*
X396041Y-326158D01*
X396056Y-326175D01*
X396073Y-326190D01*
X396088Y-326207D01*
X396106Y-326222D01*
X396121Y-326240D01*
X396138Y-326255D01*
X396153Y-326272D01*
X396170Y-326287D01*
X396205Y-326326D01*
X396234Y-326370D01*
X396248Y-326399D01*
X396250Y-326401D01*
X396267Y-326416D01*
X396301Y-326455D01*
X396330Y-326499D01*
X396354Y-326546D01*
X396356Y-326554D01*
X396363Y-326564D01*
X396377Y-326593D01*
X396398Y-326617D01*
X396427Y-326660D01*
X396450Y-326707D01*
X396453Y-326715D01*
X396460Y-326725D01*
X396483Y-326772D01*
X396485Y-326780D01*
X396492Y-326789D01*
X396515Y-326836D01*
X396518Y-326844D01*
X396524Y-326854D01*
X396547Y-326901D01*
X396564Y-326951D01*
X396569Y-326977D01*
X396580Y-326998D01*
X396596Y-327047D01*
X396602Y-327074D01*
X396612Y-327095D01*
X396629Y-327144D01*
X396634Y-327171D01*
X396644Y-327191D01*
X396661Y-327241D01*
X396671Y-327292D01*
X396672Y-327312D01*
X396676Y-327320D01*
X396693Y-327370D01*
X396703Y-327421D01*
X396707Y-327474D01*
Y-327506D01*
Y-327510D01*
X396709Y-327514D01*
X396725Y-327564D01*
X396736Y-327615D01*
X396739Y-327667D01*
Y-327700D01*
Y-327732D01*
Y-327764D01*
Y-327796D01*
Y-327829D01*
Y-327861D01*
Y-327893D01*
Y-327925D01*
Y-327958D01*
Y-327990D01*
Y-328022D01*
X396738Y-328038D01*
X396739Y-328054D01*
Y-328087D01*
X396736Y-328139D01*
X396725Y-328190D01*
X396709Y-328240D01*
X396707Y-328244D01*
Y-328248D01*
Y-328280D01*
Y-328313D01*
X396703Y-328365D01*
X396693Y-328416D01*
X396676Y-328466D01*
X396672Y-328474D01*
X396671Y-328494D01*
X396661Y-328545D01*
X396644Y-328595D01*
X396634Y-328615D01*
X396629Y-328642D01*
X396612Y-328692D01*
X396602Y-328712D01*
X396596Y-328739D01*
X396580Y-328789D01*
X396569Y-328809D01*
X396564Y-328836D01*
X396547Y-328885D01*
X396524Y-328932D01*
X396518Y-328942D01*
X396515Y-328950D01*
X396492Y-328997D01*
X396485Y-329006D01*
X396483Y-329014D01*
X396460Y-329061D01*
X396453Y-329071D01*
X396450Y-329079D01*
X396427Y-329126D01*
X396398Y-329170D01*
X396377Y-329193D01*
X396363Y-329223D01*
X396334Y-329266D01*
X396313Y-329290D01*
X396298Y-329320D01*
X396269Y-329363D01*
X396234Y-329403D01*
X396217Y-329417D01*
X396216Y-329419D01*
X396214Y-329423D01*
X396201Y-329449D01*
X396172Y-329492D01*
X396138Y-329532D01*
X396121Y-329547D01*
X396106Y-329564D01*
X396088Y-329579D01*
X396073Y-329596D01*
X396056Y-329611D01*
X396041Y-329628D01*
X396024Y-329643D01*
X396009Y-329661D01*
X395991Y-329676D01*
X395976Y-329693D01*
X395959Y-329708D01*
X395944Y-329725D01*
X395927Y-329740D01*
X395912Y-329757D01*
X395895Y-329772D01*
X395880Y-329790D01*
X395840Y-329824D01*
X395797Y-329853D01*
X395767Y-329868D01*
X395766Y-329869D01*
X395758Y-329878D01*
X395751Y-329887D01*
X395711Y-329921D01*
X395668Y-329950D01*
X395638Y-329965D01*
X395614Y-329986D01*
X395571Y-330015D01*
X395542Y-330029D01*
X395518Y-330050D01*
X395474Y-330079D01*
X395427Y-330102D01*
X395419Y-330105D01*
X395409Y-330112D01*
X395362Y-330135D01*
X395355Y-330137D01*
X395345Y-330144D01*
X395298Y-330167D01*
X395290Y-330170D01*
X395280Y-330176D01*
X395233Y-330199D01*
X395184Y-330216D01*
X395157Y-330221D01*
X395137Y-330231D01*
X395129Y-330234D01*
X395119Y-330241D01*
X395072Y-330264D01*
X395022Y-330281D01*
X394971Y-330291D01*
X394951Y-330292D01*
X394943Y-330296D01*
X394893Y-330313D01*
X394867Y-330318D01*
X394846Y-330328D01*
X394797Y-330345D01*
X394745Y-330355D01*
X394693Y-330359D01*
X394656D01*
X394653Y-330361D01*
X394603Y-330377D01*
X394552Y-330388D01*
X394499Y-330391D01*
X389785D01*
X389781Y-330393D01*
X389732Y-330410D01*
X389680Y-330420D01*
X389628Y-330423D01*
X389527D01*
X389523Y-330425D01*
X389473Y-330442D01*
X389422Y-330452D01*
X389402Y-330453D01*
X389394Y-330457D01*
X389344Y-330474D01*
X389293Y-330484D01*
X389273Y-330486D01*
X389265Y-330490D01*
X389257Y-330492D01*
X389247Y-330499D01*
X389200Y-330522D01*
X389151Y-330539D01*
X389124Y-330544D01*
X389104Y-330554D01*
X389096Y-330557D01*
X389086Y-330563D01*
X389039Y-330586D01*
X389031Y-330589D01*
X389022Y-330595D01*
X388975Y-330619D01*
X388967Y-330621D01*
X388957Y-330628D01*
X388928Y-330642D01*
X388908Y-330660D01*
X388904Y-330663D01*
X388860Y-330692D01*
X388813Y-330715D01*
X388805Y-330718D01*
X388796Y-330725D01*
X388767Y-330739D01*
X388766Y-330739D01*
X388765Y-330740D01*
X388750Y-330757D01*
X388733Y-330772D01*
X388718Y-330790D01*
X388678Y-330824D01*
X388634Y-330854D01*
X388605Y-330868D01*
X388604Y-330869D01*
X388589Y-330887D01*
X388571Y-330902D01*
X388556Y-330919D01*
X388539Y-330934D01*
X388526Y-330949D01*
X388524Y-330951D01*
X388507Y-330966D01*
X388505Y-330968D01*
X388491Y-330997D01*
X388462Y-331041D01*
X388427Y-331080D01*
X388410Y-331095D01*
X388409Y-331097D01*
X388394Y-331126D01*
X388365Y-331170D01*
X388344Y-331194D01*
X388330Y-331223D01*
X388300Y-331267D01*
X388280Y-331291D01*
X388265Y-331320D01*
X388259Y-331329D01*
X388256Y-331337D01*
X388233Y-331384D01*
X388226Y-331394D01*
X388224Y-331401D01*
X388224Y-331402D01*
X388214Y-331422D01*
X388208Y-331449D01*
X388191Y-331499D01*
X388168Y-331546D01*
X388162Y-331555D01*
X388159Y-331563D01*
X388159Y-331563D01*
X388149Y-331584D01*
X388144Y-331610D01*
X388127Y-331660D01*
X388123Y-331668D01*
X388123Y-331675D01*
X388122Y-331688D01*
X388111Y-331739D01*
X388095Y-331789D01*
X388093Y-331792D01*
Y-331797D01*
Y-331829D01*
X388089Y-331881D01*
X388079Y-331933D01*
X388062Y-331982D01*
X388061Y-331986D01*
Y-331990D01*
Y-332023D01*
Y-332055D01*
Y-332087D01*
Y-332119D01*
Y-332152D01*
Y-332184D01*
Y-332188D01*
X388062Y-332192D01*
X388079Y-332242D01*
X388089Y-332293D01*
X388093Y-332345D01*
Y-332378D01*
Y-332382D01*
X388095Y-332385D01*
X388111Y-332435D01*
X388122Y-332487D01*
X388123Y-332507D01*
X388127Y-332515D01*
X388144Y-332564D01*
X388149Y-332591D01*
X388159Y-332611D01*
X388176Y-332661D01*
X388181Y-332688D01*
X388184Y-332692D01*
X388191Y-332708D01*
X388194Y-332716D01*
X388200Y-332726D01*
X388224Y-332773D01*
X388226Y-332781D01*
X388233Y-332790D01*
X388256Y-332837D01*
X388259Y-332845D01*
X388265Y-332855D01*
X388288Y-332902D01*
X388291Y-332910D01*
X388297Y-332919D01*
X388312Y-332948D01*
X388320Y-332958D01*
X388333Y-332972D01*
X388362Y-333016D01*
X388376Y-333045D01*
X388397Y-333069D01*
X388426Y-333113D01*
X388441Y-333142D01*
X388442Y-333144D01*
X388452Y-333152D01*
X388459Y-333159D01*
X388474Y-333176D01*
X388492Y-333191D01*
X388507Y-333208D01*
X388508Y-333209D01*
X388524Y-333223D01*
X388539Y-333241D01*
X388556Y-333256D01*
X388571Y-333273D01*
X388589Y-333288D01*
X388603Y-333305D01*
X388607Y-333308D01*
X388621Y-333320D01*
X388636Y-333337D01*
X388653Y-333352D01*
X388668Y-333369D01*
X388677Y-333378D01*
X388685Y-333385D01*
X388700Y-333402D01*
X388702Y-333403D01*
X388731Y-333418D01*
X388775Y-333447D01*
X388799Y-333468D01*
X388828Y-333482D01*
X388872Y-333511D01*
X388882Y-333521D01*
X388896Y-333532D01*
X388925Y-333547D01*
X388934Y-333553D01*
X388942Y-333556D01*
X388989Y-333579D01*
X388999Y-333585D01*
X389007Y-333588D01*
X389054Y-333611D01*
X389063Y-333618D01*
X389071Y-333620D01*
X389118Y-333644D01*
X389128Y-333650D01*
X389136Y-333653D01*
X389153Y-333661D01*
X389156Y-333663D01*
X389183Y-333668D01*
X389233Y-333685D01*
X389250Y-333693D01*
X389253Y-333695D01*
X389280Y-333700D01*
X389330Y-333717D01*
X389337Y-333721D01*
X389357Y-333722D01*
X389409Y-333733D01*
X389458Y-333749D01*
X389462Y-333751D01*
X389466D01*
X389519Y-333754D01*
X389570Y-333765D01*
X389620Y-333782D01*
X389623Y-333783D01*
X414986D01*
X415002Y-333784D01*
X415018Y-333783D01*
X415050D01*
X415102Y-333787D01*
X415154Y-333797D01*
X415203Y-333814D01*
X415207Y-333816D01*
X415276D01*
X415328Y-333819D01*
X415380Y-333829D01*
X415429Y-333846D01*
X415437Y-333850D01*
X415457Y-333851D01*
X415509Y-333861D01*
X415558Y-333878D01*
X415579Y-333889D01*
X415605Y-333894D01*
X415655Y-333911D01*
X415670Y-333918D01*
X415676Y-333921D01*
X415702Y-333926D01*
X415752Y-333943D01*
X415767Y-333950D01*
X415772Y-333953D01*
X415799Y-333958D01*
X415849Y-333975D01*
X415896Y-333998D01*
X415905Y-334005D01*
X415905Y-334005D01*
X415913Y-334007D01*
X415960Y-334031D01*
X415970Y-334037D01*
X415978Y-334040D01*
X416025Y-334063D01*
X416034Y-334069D01*
X416038Y-334071D01*
X416042Y-334072D01*
X416089Y-334095D01*
X416099Y-334102D01*
X416107Y-334104D01*
X416154Y-334127D01*
X416197Y-334156D01*
X416221Y-334177D01*
X416251Y-334192D01*
X416294Y-334221D01*
X416318Y-334242D01*
X416347Y-334257D01*
X416391Y-334286D01*
X416430Y-334320D01*
X416445Y-334337D01*
X416463Y-334352D01*
X416478Y-334370D01*
X416479Y-334371D01*
X416509Y-334385D01*
X416552Y-334415D01*
X416592Y-334449D01*
X416607Y-334466D01*
X416624Y-334482D01*
X416639Y-334499D01*
X416656Y-334514D01*
X416671Y-334531D01*
X416688Y-334546D01*
X416704Y-334563D01*
X416721Y-334578D01*
X416721Y-334578D01*
X416736Y-334595D01*
X416753Y-334611D01*
X416788Y-334650D01*
X416817Y-334694D01*
X416831Y-334723D01*
X416833Y-334724D01*
X416850Y-334740D01*
X416865Y-334757D01*
X416882Y-334772D01*
X416917Y-334811D01*
X416946Y-334855D01*
X416960Y-334884D01*
X416965Y-334889D01*
X416981Y-334908D01*
X417010Y-334952D01*
X417025Y-334981D01*
X417040Y-334999D01*
X417046Y-335005D01*
X417075Y-335048D01*
X417098Y-335095D01*
X417101Y-335103D01*
X417107Y-335113D01*
X417130Y-335160D01*
X417133Y-335168D01*
X417139Y-335177D01*
X417163Y-335225D01*
X417165Y-335232D01*
X417172Y-335242D01*
X417195Y-335289D01*
X417212Y-335339D01*
X417217Y-335365D01*
X417227Y-335386D01*
X417230Y-335394D01*
X417236Y-335403D01*
X417259Y-335450D01*
X417276Y-335500D01*
X417281Y-335525D01*
X417281Y-335527D01*
X417285Y-335535D01*
X417292Y-335547D01*
X417308Y-335597D01*
X417319Y-335648D01*
X417320Y-335668D01*
X417324Y-335676D01*
X417341Y-335726D01*
X417351Y-335777D01*
X417354Y-335830D01*
Y-335834D01*
X417356Y-335838D01*
X417373Y-335887D01*
X417383Y-335939D01*
X417387Y-335991D01*
Y-336023D01*
Y-336055D01*
Y-336088D01*
D01*
Y-336120D01*
Y-336152D01*
Y-336184D01*
Y-336217D01*
Y-336249D01*
Y-336281D01*
Y-336314D01*
Y-336346D01*
Y-336378D01*
Y-336410D01*
Y-336442D01*
Y-336475D01*
Y-336507D01*
Y-336539D01*
Y-336572D01*
Y-336604D01*
X417383Y-336656D01*
X417373Y-336708D01*
X417356Y-336757D01*
X417354Y-336761D01*
Y-336765D01*
X417351Y-336818D01*
X417341Y-336869D01*
X417324Y-336919D01*
X417320Y-336926D01*
X417319Y-336947D01*
X417308Y-336998D01*
X417292Y-337048D01*
X417281Y-337068D01*
X417277Y-337088D01*
X417276Y-337095D01*
X417259Y-337144D01*
X417249Y-337165D01*
X417244Y-337192D01*
X417227Y-337241D01*
X417204Y-337288D01*
X417198Y-337298D01*
X417195Y-337306D01*
X417172Y-337353D01*
X417166Y-337361D01*
X417165Y-337362D01*
X417163Y-337370D01*
X417139Y-337417D01*
X417133Y-337427D01*
X417130Y-337435D01*
X417107Y-337482D01*
X417101Y-337491D01*
X417098Y-337499D01*
X417075Y-337546D01*
X417068Y-337556D01*
X417066Y-337564D01*
X417043Y-337611D01*
X417013Y-337654D01*
X416993Y-337678D01*
X416981Y-337701D01*
X416978Y-337708D01*
X416949Y-337751D01*
X416914Y-337791D01*
X416897Y-337806D01*
X416882Y-337823D01*
X416865Y-337838D01*
X416863Y-337840D01*
X416852Y-337862D01*
X416849Y-337869D01*
X416820Y-337913D01*
X416785Y-337952D01*
X416768Y-337967D01*
X416753Y-337984D01*
X416736Y-337999D01*
X416721Y-338016D01*
X416704Y-338032D01*
X416688Y-338049D01*
X416671Y-338064D01*
X416663Y-338074D01*
X416656Y-338081D01*
X416639Y-338096D01*
X416624Y-338113D01*
X416607Y-338128D01*
X416592Y-338145D01*
X416575Y-338160D01*
X416560Y-338178D01*
X416542Y-338193D01*
X416527Y-338210D01*
X416488Y-338245D01*
X416444Y-338274D01*
X416429Y-338281D01*
X416415Y-338288D01*
X416413Y-338290D01*
X416398Y-338307D01*
X416359Y-338341D01*
X416315Y-338370D01*
X416286Y-338385D01*
X416262Y-338406D01*
X416218Y-338435D01*
X416171Y-338458D01*
X416163Y-338461D01*
X416154Y-338467D01*
X416124Y-338482D01*
X416101Y-338503D01*
X416057Y-338532D01*
X416010Y-338555D01*
X415960Y-338572D01*
X415934Y-338577D01*
X415913Y-338587D01*
X415905Y-338590D01*
X415896Y-338596D01*
X415849Y-338619D01*
X415841Y-338622D01*
X415831Y-338629D01*
X415784Y-338652D01*
X415734Y-338669D01*
X415708Y-338674D01*
X415687Y-338684D01*
X415638Y-338701D01*
X415611Y-338706D01*
X415591Y-338716D01*
X415541Y-338733D01*
X415489Y-338743D01*
X415469Y-338745D01*
X415461Y-338749D01*
X415412Y-338765D01*
X415360Y-338776D01*
X415308Y-338779D01*
X415272D01*
X415268Y-338781D01*
X415218Y-338798D01*
X415167Y-338808D01*
X415115Y-338811D01*
X398528D01*
X398524Y-338813D01*
X398474Y-338830D01*
X398423Y-338840D01*
X398371Y-338844D01*
X398334D01*
X398330Y-338845D01*
X398281Y-338862D01*
X398229Y-338872D01*
X398209Y-338874D01*
X398201Y-338878D01*
X398152Y-338895D01*
X398100Y-338905D01*
X398080Y-338906D01*
X398072Y-338910D01*
X398064Y-338913D01*
X398055Y-338919D01*
X398008Y-338942D01*
X397958Y-338959D01*
X397932Y-338964D01*
X397911Y-338974D01*
X397903Y-338977D01*
X397898Y-338981D01*
X397894Y-338983D01*
X397847Y-339007D01*
X397839Y-339009D01*
X397829Y-339016D01*
X397782Y-339039D01*
X397774Y-339042D01*
X397771Y-339043D01*
X397765Y-339048D01*
X397735Y-339062D01*
X397731Y-339066D01*
X397711Y-339083D01*
X397668Y-339112D01*
X397639Y-339127D01*
X397637Y-339128D01*
X397622Y-339146D01*
X397582Y-339180D01*
X397539Y-339209D01*
X397510Y-339224D01*
X397508Y-339225D01*
X397494Y-339241D01*
X397493Y-339242D01*
X397476Y-339258D01*
X397461Y-339275D01*
X397443Y-339290D01*
X397428Y-339307D01*
X397411Y-339322D01*
X397396Y-339339D01*
X397379Y-339354D01*
X397379Y-339354D01*
X397364Y-339371D01*
X397346Y-339387D01*
X397331Y-339404D01*
X397314Y-339419D01*
X397299Y-339436D01*
X397282Y-339451D01*
X397281Y-339453D01*
X397270Y-339475D01*
X397266Y-339482D01*
X397237Y-339526D01*
X397216Y-339549D01*
X397201Y-339579D01*
X397172Y-339622D01*
X397151Y-339646D01*
X397137Y-339676D01*
X397131Y-339685D01*
X397128Y-339693D01*
X397105Y-339740D01*
X397098Y-339750D01*
X397096Y-339758D01*
X397073Y-339805D01*
X397066Y-339814D01*
X397063Y-339822D01*
X397040Y-339869D01*
X397034Y-339879D01*
X397031Y-339887D01*
X397021Y-339907D01*
X397016Y-339934D01*
X396999Y-339983D01*
X396989Y-340004D01*
X396984Y-340031D01*
X396967Y-340080D01*
X396963Y-340088D01*
X396961Y-340108D01*
X396951Y-340160D01*
X396934Y-340209D01*
X396933Y-340213D01*
Y-340217D01*
Y-340249D01*
X396929Y-340302D01*
X396919Y-340353D01*
X396902Y-340403D01*
X396900Y-340406D01*
Y-340411D01*
Y-340443D01*
Y-340475D01*
Y-340508D01*
Y-340540D01*
Y-340572D01*
Y-340604D01*
Y-340609D01*
X396902Y-340612D01*
X396919Y-340662D01*
X396929Y-340713D01*
X396933Y-340766D01*
Y-340798D01*
Y-340802D01*
X396934Y-340806D01*
X396951Y-340855D01*
X396961Y-340907D01*
X396963Y-340927D01*
X396967Y-340935D01*
X396984Y-340985D01*
X396988Y-341005D01*
X396989Y-341011D01*
X396999Y-341032D01*
X397016Y-341081D01*
X397021Y-341108D01*
X397031Y-341127D01*
X397031Y-341128D01*
X397034Y-341136D01*
X397039Y-341145D01*
X397040Y-341146D01*
X397063Y-341193D01*
X397066Y-341201D01*
X397073Y-341210D01*
X397096Y-341258D01*
X397098Y-341265D01*
X397105Y-341275D01*
X397128Y-341322D01*
X397131Y-341330D01*
X397136Y-341338D01*
X397137Y-341339D01*
X397151Y-341369D01*
X397160Y-341378D01*
X397172Y-341393D01*
X397201Y-341436D01*
X397216Y-341466D01*
X397217Y-341467D01*
X397235Y-341482D01*
X397269Y-341522D01*
X397298Y-341565D01*
X397311Y-341590D01*
X397313Y-341595D01*
X397314Y-341596D01*
X397331Y-341611D01*
X397346Y-341629D01*
X397364Y-341644D01*
X397379Y-341661D01*
X397396Y-341676D01*
X397411Y-341693D01*
X397412Y-341694D01*
X397428Y-341708D01*
X397443Y-341725D01*
X397461Y-341740D01*
X397476Y-341758D01*
X397476Y-341758D01*
X397477Y-341759D01*
X397481Y-341761D01*
X397506Y-341774D01*
X397550Y-341803D01*
X397589Y-341837D01*
X397604Y-341854D01*
X397606Y-341856D01*
X397636Y-341870D01*
X397679Y-341899D01*
X397703Y-341920D01*
X397732Y-341935D01*
X397742Y-341941D01*
X397750Y-341944D01*
X397797Y-341967D01*
X397840Y-341996D01*
X397864Y-342017D01*
X397867Y-342019D01*
X397894Y-342024D01*
X397943Y-342041D01*
X397990Y-342064D01*
X398000Y-342070D01*
X398008Y-342073D01*
X398028Y-342083D01*
X398055Y-342088D01*
X398105Y-342105D01*
X398125Y-342115D01*
X398152Y-342121D01*
X398201Y-342137D01*
X398209Y-342141D01*
X398229Y-342143D01*
X398281Y-342153D01*
X398330Y-342170D01*
X398334Y-342171D01*
X398403D01*
X398455Y-342175D01*
X398507Y-342185D01*
X398556Y-342202D01*
X398560Y-342204D01*
X404597D01*
X404649Y-342207D01*
X404701Y-342217D01*
X404751Y-342234D01*
X404754Y-342236D01*
X404759D01*
X404811Y-342239D01*
X404862Y-342250D01*
X404912Y-342266D01*
X404920Y-342270D01*
X404940Y-342272D01*
X404991Y-342282D01*
X405041Y-342299D01*
X405061Y-342309D01*
X405088Y-342314D01*
X405138Y-342331D01*
X405158Y-342341D01*
X405185Y-342346D01*
X405235Y-342363D01*
X405255Y-342373D01*
X405282Y-342379D01*
X405331Y-342395D01*
X405378Y-342419D01*
X405388Y-342425D01*
X405396Y-342428D01*
X405443Y-342451D01*
X405452Y-342457D01*
X405460Y-342460D01*
X405507Y-342483D01*
X405517Y-342490D01*
X405525Y-342492D01*
X405572Y-342515D01*
X405581Y-342522D01*
X405589Y-342525D01*
X405637Y-342548D01*
X405680Y-342577D01*
X405691Y-342586D01*
X405704Y-342598D01*
X405733Y-342612D01*
X405777Y-342641D01*
X405816Y-342676D01*
X405831Y-342693D01*
X405833Y-342695D01*
X405862Y-342709D01*
X405906Y-342738D01*
X405945Y-342773D01*
X405960Y-342790D01*
X405965Y-342793D01*
X405978Y-342805D01*
X405993Y-342822D01*
X406010Y-342837D01*
X406025Y-342854D01*
X406042Y-342869D01*
X406057Y-342887D01*
X406074Y-342902D01*
X406089Y-342919D01*
X406107Y-342934D01*
X406122Y-342951D01*
X406139Y-342966D01*
X406154Y-342984D01*
X406171Y-342999D01*
X406186Y-343016D01*
X406195Y-343024D01*
X406203Y-343031D01*
X406219Y-343048D01*
X406236Y-343063D01*
X406251Y-343080D01*
X406268Y-343095D01*
X406283Y-343112D01*
X406300Y-343128D01*
X406335Y-343167D01*
X406364Y-343211D01*
X406378Y-343240D01*
X406380Y-343242D01*
X406397Y-343257D01*
X406432Y-343296D01*
X406461Y-343340D01*
X406484Y-343387D01*
X406487Y-343395D01*
X406493Y-343404D01*
X406505Y-343429D01*
X406507Y-343433D01*
X406528Y-343457D01*
X406558Y-343501D01*
X406581Y-343548D01*
X406583Y-343556D01*
X406590Y-343566D01*
X406613Y-343613D01*
X406616Y-343621D01*
X406622Y-343630D01*
X406645Y-343677D01*
X406662Y-343727D01*
X406667Y-343753D01*
X406677Y-343774D01*
X406680Y-343782D01*
X406684Y-343788D01*
X406686Y-343791D01*
X406710Y-343838D01*
X406727Y-343888D01*
X406732Y-343915D01*
X406742Y-343935D01*
X406759Y-343985D01*
X406769Y-344036D01*
X406770Y-344056D01*
X406774Y-344064D01*
X406791Y-344114D01*
X406801Y-344165D01*
X406805Y-344218D01*
Y-344222D01*
X406807Y-344226D01*
X406823Y-344275D01*
X406834Y-344327D01*
X406837Y-344379D01*
Y-344411D01*
Y-344443D01*
Y-344476D01*
Y-344508D01*
Y-344540D01*
Y-344572D01*
Y-344605D01*
Y-344637D01*
Y-344669D01*
Y-344702D01*
Y-344734D01*
Y-344766D01*
Y-344798D01*
Y-344831D01*
Y-344863D01*
D01*
Y-344895D01*
Y-344927D01*
Y-344960D01*
Y-344992D01*
D01*
Y-345024D01*
Y-345056D01*
X406834Y-345109D01*
X406823Y-345160D01*
X406807Y-345210D01*
X406805Y-345213D01*
Y-345218D01*
X406801Y-345270D01*
X406791Y-345321D01*
X406774Y-345371D01*
X406764Y-345392D01*
X406759Y-345418D01*
X406742Y-345468D01*
X406732Y-345488D01*
X406727Y-345515D01*
X406710Y-345565D01*
X406700Y-345585D01*
X406694Y-345612D01*
X406677Y-345661D01*
X406654Y-345708D01*
X406648Y-345718D01*
X406645Y-345726D01*
X406622Y-345773D01*
X406616Y-345782D01*
X406613Y-345791D01*
X406590Y-345838D01*
X406583Y-345847D01*
X406581Y-345855D01*
X406558Y-345902D01*
X406551Y-345912D01*
X406548Y-345920D01*
X406525Y-345967D01*
X406519Y-345976D01*
X406518Y-345980D01*
X406516Y-345984D01*
X406493Y-346031D01*
X406464Y-346075D01*
X406443Y-346099D01*
X406428Y-346128D01*
X406399Y-346171D01*
X406365Y-346211D01*
X406348Y-346226D01*
X406332Y-346243D01*
X406315Y-346258D01*
X406314Y-346260D01*
X406299Y-346289D01*
X406270Y-346333D01*
X406236Y-346372D01*
X406218Y-346387D01*
X406203Y-346405D01*
X406186Y-346420D01*
X406171Y-346437D01*
X406154Y-346452D01*
X406139Y-346469D01*
X406122Y-346484D01*
X406107Y-346501D01*
X406089Y-346516D01*
X406074Y-346534D01*
X406057Y-346549D01*
X406042Y-346566D01*
X406025Y-346581D01*
X406025Y-346581D01*
X406010Y-346598D01*
X405970Y-346633D01*
X405927Y-346662D01*
X405898Y-346676D01*
X405896Y-346678D01*
X405881Y-346695D01*
X405841Y-346729D01*
X405798Y-346759D01*
X405768Y-346773D01*
X405745Y-346794D01*
X405701Y-346823D01*
X405672Y-346837D01*
X405662Y-346846D01*
X405648Y-346859D01*
X405604Y-346888D01*
X405557Y-346911D01*
X405549Y-346914D01*
X405540Y-346920D01*
X405493Y-346943D01*
X405485Y-346946D01*
X405475Y-346952D01*
X405428Y-346975D01*
X405420Y-346978D01*
X405411Y-346984D01*
X405364Y-347008D01*
X405356Y-347010D01*
X405346Y-347017D01*
X405299Y-347040D01*
X405249Y-347057D01*
X405223Y-347062D01*
X405202Y-347072D01*
X405153Y-347089D01*
X405126Y-347094D01*
X405105Y-347104D01*
X405056Y-347121D01*
X405029Y-347127D01*
X405009Y-347137D01*
X404959Y-347153D01*
X404908Y-347164D01*
X404855Y-347167D01*
X404851D01*
X404847Y-347169D01*
X404798Y-347186D01*
X404746Y-347196D01*
X404694Y-347199D01*
X404625D01*
X404622Y-347201D01*
X404572Y-347218D01*
X404521Y-347228D01*
X404468Y-347232D01*
X404404D01*
X404388Y-347231D01*
X404371Y-347232D01*
X394693D01*
X394677Y-347231D01*
X394661Y-347232D01*
X394495D01*
X394491Y-347233D01*
X394442Y-347250D01*
X394390Y-347260D01*
X394338Y-347264D01*
X394334D01*
X394330Y-347266D01*
X394280Y-347283D01*
X394229Y-347293D01*
X394209Y-347294D01*
X394201Y-347298D01*
X394151Y-347315D01*
X394125Y-347320D01*
X394104Y-347330D01*
X394096Y-347333D01*
X394087Y-347339D01*
X394040Y-347362D01*
X393990Y-347379D01*
X393963Y-347385D01*
X393959Y-347387D01*
X393943Y-347395D01*
X393935Y-347397D01*
X393925Y-347404D01*
X393896Y-347418D01*
X393875Y-347437D01*
X393872Y-347439D01*
X393829Y-347468D01*
X393782Y-347492D01*
X393774Y-347494D01*
X393764Y-347501D01*
X393735Y-347515D01*
X393711Y-347536D01*
X393667Y-347565D01*
X393638Y-347580D01*
X393636Y-347581D01*
X393621Y-347598D01*
X393604Y-347613D01*
X393589Y-347631D01*
X393550Y-347665D01*
X393506Y-347694D01*
X393477Y-347709D01*
X393475Y-347710D01*
X393460Y-347727D01*
X393443Y-347742D01*
X393441Y-347744D01*
X393427Y-347773D01*
X393398Y-347817D01*
X393363Y-347856D01*
X393346Y-347871D01*
X393331Y-347889D01*
X393314Y-347904D01*
X393312Y-347905D01*
X393305Y-347920D01*
X393298Y-347935D01*
X393269Y-347978D01*
X393250Y-348000D01*
X393248Y-348002D01*
X393233Y-348031D01*
X393204Y-348075D01*
X393183Y-348099D01*
X393169Y-348128D01*
X393162Y-348138D01*
X393160Y-348146D01*
X393137Y-348193D01*
X393130Y-348202D01*
X393127Y-348210D01*
X393104Y-348257D01*
X393098Y-348267D01*
X393095Y-348275D01*
X393085Y-348295D01*
X393081Y-348315D01*
X393080Y-348322D01*
X393063Y-348372D01*
X393053Y-348392D01*
X393048Y-348419D01*
X393031Y-348468D01*
X393021Y-348489D01*
X393015Y-348515D01*
X392999Y-348565D01*
X392997Y-348569D01*
Y-348573D01*
X392993Y-348625D01*
X392983Y-348677D01*
X392966Y-348726D01*
X392964Y-348730D01*
Y-348734D01*
Y-348766D01*
Y-348799D01*
Y-348831D01*
Y-348863D01*
Y-348896D01*
Y-348928D01*
Y-348960D01*
Y-348992D01*
Y-349025D01*
Y-349057D01*
Y-349089D01*
Y-349094D01*
X392966Y-349097D01*
X392983Y-349147D01*
X392993Y-349198D01*
X392997Y-349251D01*
Y-349255D01*
X392999Y-349258D01*
X393015Y-349308D01*
X393021Y-349335D01*
X393031Y-349355D01*
X393048Y-349405D01*
X393053Y-349431D01*
X393063Y-349452D01*
X393080Y-349502D01*
X393085Y-349528D01*
X393095Y-349549D01*
X393098Y-349557D01*
X393104Y-349566D01*
X393127Y-349613D01*
X393130Y-349621D01*
X393137Y-349631D01*
X393160Y-349678D01*
X393162Y-349686D01*
X393169Y-349695D01*
X393192Y-349742D01*
X393195Y-349750D01*
X393201Y-349760D01*
X393216Y-349789D01*
X393236Y-349813D01*
X393266Y-349857D01*
X393280Y-349886D01*
X393282Y-349887D01*
X393299Y-349903D01*
X393333Y-349942D01*
X393362Y-349986D01*
X393377Y-350015D01*
X393378Y-350016D01*
X393395Y-350032D01*
X393411Y-350049D01*
X393428Y-350064D01*
X393443Y-350081D01*
X393460Y-350096D01*
X393475Y-350113D01*
X393492Y-350128D01*
X393507Y-350146D01*
X393525Y-350161D01*
X393540Y-350178D01*
X393541Y-350179D01*
X393555Y-350186D01*
X393571Y-350194D01*
X393614Y-350223D01*
X393654Y-350257D01*
X393669Y-350275D01*
X393670Y-350276D01*
X393700Y-350291D01*
X393743Y-350320D01*
X393767Y-350341D01*
X393796Y-350355D01*
X393806Y-350361D01*
X393814Y-350364D01*
X393861Y-350387D01*
X393870Y-350394D01*
X393878Y-350396D01*
X393925Y-350420D01*
X393935Y-350426D01*
X393943Y-350429D01*
X393990Y-350452D01*
X394000Y-350458D01*
X394007Y-350461D01*
X394028Y-350471D01*
X394055Y-350476D01*
X394104Y-350493D01*
X394151Y-350516D01*
X394161Y-350523D01*
X394169Y-350525D01*
X394177Y-350529D01*
X394197Y-350531D01*
X394248Y-350541D01*
X394298Y-350558D01*
X394301Y-350559D01*
X394306D01*
X394358Y-350563D01*
X394409Y-350573D01*
X394459Y-350590D01*
X394463Y-350592D01*
X394596D01*
X394648Y-350595D01*
X394700Y-350605D01*
X394749Y-350622D01*
X394753Y-350624D01*
X401274D01*
X401327Y-350627D01*
X401378Y-350638D01*
X401428Y-350655D01*
X401431Y-350656D01*
X401436D01*
X401488Y-350660D01*
X401539Y-350670D01*
X401589Y-350687D01*
X401610Y-350697D01*
X401636Y-350702D01*
X401686Y-350719D01*
X401706Y-350729D01*
X401733Y-350734D01*
X401783Y-350751D01*
X401803Y-350761D01*
X401830Y-350767D01*
X401879Y-350784D01*
X401890Y-350789D01*
X401900Y-350794D01*
X401927Y-350799D01*
X401976Y-350816D01*
X402023Y-350839D01*
X402033Y-350845D01*
X402041Y-350848D01*
X402088Y-350871D01*
X402097Y-350878D01*
X402105Y-350880D01*
X402152Y-350904D01*
X402196Y-350933D01*
X402220Y-350954D01*
X402247Y-350967D01*
X402249Y-350968D01*
X402258Y-350974D01*
X402267Y-350977D01*
X402314Y-351000D01*
X402357Y-351029D01*
X402381Y-351050D01*
X402410Y-351065D01*
X402454Y-351094D01*
X402493Y-351129D01*
X402508Y-351146D01*
X402526Y-351161D01*
X402541Y-351178D01*
X402542Y-351179D01*
X402572Y-351194D01*
X402615Y-351223D01*
X402655Y-351258D01*
X402670Y-351275D01*
X402687Y-351290D01*
X402702Y-351307D01*
X402719Y-351322D01*
X402725Y-351329D01*
X402734Y-351339D01*
X402751Y-351354D01*
X402766Y-351372D01*
X402784Y-351387D01*
X402799Y-351404D01*
X402816Y-351419D01*
X402850Y-351458D01*
X402880Y-351502D01*
X402891Y-351526D01*
X402894Y-351531D01*
X402895Y-351533D01*
X402911Y-351546D01*
X402913Y-351548D01*
X402928Y-351565D01*
X402945Y-351580D01*
X402980Y-351620D01*
X403009Y-351663D01*
X403023Y-351693D01*
X403044Y-351716D01*
X403073Y-351760D01*
X403088Y-351789D01*
X403109Y-351813D01*
X403138Y-351857D01*
X403161Y-351904D01*
X403164Y-351912D01*
X403170Y-351921D01*
X403193Y-351968D01*
X403196Y-351976D01*
X403202Y-351986D01*
X403226Y-352033D01*
X403228Y-352041D01*
X403234Y-352050D01*
X403258Y-352097D01*
X403260Y-352105D01*
X403265Y-352112D01*
X403267Y-352115D01*
X403290Y-352162D01*
X403307Y-352212D01*
X403312Y-352238D01*
X403322Y-352259D01*
X403339Y-352308D01*
X403344Y-352335D01*
X403355Y-352356D01*
X403371Y-352405D01*
X403377Y-352432D01*
X403387Y-352452D01*
X403404Y-352502D01*
X403414Y-352553D01*
X403417Y-352606D01*
Y-352638D01*
Y-352642D01*
X403419Y-352646D01*
X403436Y-352695D01*
X403446Y-352747D01*
X403449Y-352799D01*
Y-352832D01*
Y-352864D01*
Y-352896D01*
Y-352928D01*
Y-352933D01*
X403451Y-352936D01*
X403468Y-352986D01*
X403478Y-353037D01*
X403482Y-353090D01*
Y-353122D01*
Y-353154D01*
X403478Y-353206D01*
X403468Y-353258D01*
X403451Y-353308D01*
X403449Y-353311D01*
Y-353315D01*
Y-353348D01*
Y-353380D01*
Y-353412D01*
Y-353445D01*
Y-353477D01*
X403446Y-353529D01*
X403436Y-353580D01*
X403419Y-353630D01*
X403417Y-353634D01*
Y-353638D01*
X403414Y-353690D01*
X403404Y-353742D01*
X403387Y-353791D01*
X403377Y-353812D01*
X403371Y-353839D01*
X403355Y-353888D01*
X403344Y-353909D01*
X403339Y-353935D01*
X403322Y-353985D01*
X403312Y-354006D01*
X403307Y-354032D01*
X403290Y-354082D01*
X403280Y-354102D01*
X403274Y-354129D01*
X403258Y-354179D01*
X403234Y-354226D01*
X403228Y-354235D01*
X403226Y-354243D01*
X403202Y-354290D01*
X403196Y-354300D01*
X403193Y-354308D01*
X403170Y-354355D01*
X403164Y-354364D01*
X403161Y-354372D01*
X403138Y-354419D01*
X403109Y-354463D01*
X403088Y-354487D01*
X403073Y-354516D01*
X403044Y-354560D01*
X403023Y-354584D01*
X403009Y-354613D01*
X402980Y-354656D01*
X402945Y-354696D01*
X402928Y-354711D01*
X402926Y-354713D01*
X402923Y-354719D01*
X402912Y-354742D01*
X402883Y-354785D01*
X402848Y-354825D01*
X402831Y-354840D01*
X402816Y-354857D01*
X402799Y-354872D01*
X402784Y-354889D01*
X402766Y-354905D01*
X402751Y-354922D01*
X402734Y-354937D01*
X402719Y-354954D01*
X402702Y-354969D01*
X402687Y-354986D01*
X402670Y-355001D01*
X402655Y-355018D01*
X402637Y-355033D01*
X402623Y-355049D01*
X402622Y-355051D01*
X402605Y-355066D01*
X402590Y-355083D01*
X402573Y-355098D01*
X402558Y-355115D01*
X402541Y-355130D01*
X402526Y-355148D01*
X402486Y-355182D01*
X402443Y-355211D01*
X402413Y-355226D01*
X402412Y-355227D01*
X402396Y-355244D01*
X402357Y-355279D01*
X402314Y-355308D01*
X402284Y-355322D01*
X402260Y-355343D01*
X402217Y-355373D01*
X402170Y-355396D01*
X402162Y-355398D01*
X402152Y-355405D01*
X402105Y-355428D01*
X402097Y-355431D01*
X402088Y-355437D01*
X402041Y-355460D01*
X402033Y-355463D01*
X402023Y-355469D01*
X401976Y-355492D01*
X401968Y-355495D01*
X401959Y-355502D01*
X401912Y-355525D01*
X401862Y-355542D01*
X401835Y-355547D01*
X401815Y-355557D01*
X401765Y-355574D01*
X401714Y-355584D01*
X401694Y-355585D01*
X401686Y-355589D01*
X401636Y-355606D01*
X401585Y-355616D01*
X401532Y-355620D01*
X378511D01*
Y-355638D01*
Y-355671D01*
Y-355703D01*
Y-355735D01*
Y-355767D01*
Y-355800D01*
Y-355832D01*
Y-355864D01*
Y-355896D01*
Y-355929D01*
Y-355961D01*
Y-355993D01*
Y-356025D01*
Y-356058D01*
Y-356090D01*
Y-356122D01*
Y-356154D01*
Y-356187D01*
Y-356219D01*
Y-356251D01*
Y-356283D01*
Y-356316D01*
Y-356348D01*
Y-356380D01*
Y-356413D01*
Y-356445D01*
Y-356477D01*
Y-356509D01*
Y-356542D01*
Y-356574D01*
Y-356606D01*
Y-356638D01*
Y-356671D01*
Y-356703D01*
Y-356735D01*
Y-356768D01*
Y-356800D01*
Y-356832D01*
Y-356864D01*
Y-356896D01*
Y-356929D01*
Y-356961D01*
Y-356993D01*
Y-357026D01*
Y-357058D01*
Y-357090D01*
Y-357122D01*
Y-357155D01*
Y-357187D01*
Y-357219D01*
Y-357251D01*
Y-357284D01*
Y-357316D01*
Y-357348D01*
Y-357380D01*
Y-357413D01*
Y-357445D01*
Y-357477D01*
Y-357509D01*
Y-357542D01*
Y-357574D01*
Y-357606D01*
Y-357639D01*
Y-357671D01*
Y-357703D01*
Y-357735D01*
Y-357768D01*
Y-357800D01*
Y-357832D01*
Y-357864D01*
Y-357897D01*
Y-357929D01*
Y-357961D01*
Y-357993D01*
Y-358026D01*
Y-358058D01*
Y-358090D01*
Y-358122D01*
Y-358155D01*
Y-358187D01*
Y-358219D01*
Y-358252D01*
Y-358284D01*
Y-358316D01*
Y-358348D01*
Y-358381D01*
Y-358413D01*
Y-358445D01*
Y-358477D01*
Y-358510D01*
Y-358542D01*
Y-358574D01*
Y-358606D01*
X378508Y-358659D01*
X378498Y-358710D01*
X378481Y-358760D01*
X378457Y-358807D01*
X378451Y-358816D01*
X378448Y-358824D01*
X378425Y-358871D01*
X378419Y-358881D01*
X378416Y-358889D01*
X378393Y-358936D01*
X378364Y-358979D01*
X378329Y-359019D01*
X378312Y-359034D01*
X378297Y-359051D01*
X378257Y-359086D01*
X378214Y-359115D01*
X378167Y-359138D01*
X378159Y-359141D01*
X378149Y-359147D01*
X378102Y-359170D01*
X378094Y-359173D01*
X378085Y-359179D01*
X378038Y-359203D01*
X377988Y-359219D01*
X377937Y-359230D01*
X377885Y-359233D01*
X371723D01*
X371670Y-359230D01*
X371619Y-359219D01*
X371569Y-359203D01*
X371549Y-359192D01*
X371522Y-359187D01*
X371472Y-359170D01*
X371425Y-359147D01*
X371382Y-359118D01*
X371342Y-359083D01*
X371336Y-359076D01*
X371327Y-359066D01*
X371310Y-359051D01*
X371295Y-359034D01*
X371278Y-359019D01*
X371263Y-359002D01*
X371245Y-358987D01*
X371211Y-358947D01*
X371195Y-358923D01*
X371167Y-358954D01*
X371150Y-358969D01*
X371135Y-358987D01*
X371118Y-359002D01*
X371103Y-359019D01*
X371085Y-359034D01*
X371070Y-359051D01*
X371053Y-359066D01*
X371038Y-359083D01*
X370999Y-359118D01*
X370955Y-359147D01*
X370908Y-359170D01*
X370858Y-359187D01*
X370832Y-359192D01*
X370811Y-359203D01*
X370762Y-359219D01*
X370710Y-359230D01*
X370658Y-359233D01*
X367496D01*
X367444Y-359230D01*
X367392Y-359219D01*
X367343Y-359203D01*
X367296Y-359179D01*
X367286Y-359173D01*
X367278Y-359170D01*
X367231Y-359147D01*
X367222Y-359141D01*
X367214Y-359138D01*
X367167Y-359115D01*
X367123Y-359086D01*
X367084Y-359051D01*
X367069Y-359034D01*
X367051Y-359019D01*
X367017Y-358979D01*
X366988Y-358936D01*
X366965Y-358889D01*
X366962Y-358881D01*
X366955Y-358871D01*
X366932Y-358824D01*
X366915Y-358775D01*
X366910Y-358748D01*
X366900Y-358728D01*
X366883Y-358678D01*
X366873Y-358626D01*
X366869Y-358574D01*
Y-358542D01*
Y-358510D01*
Y-358477D01*
Y-358445D01*
Y-358413D01*
Y-358381D01*
Y-358348D01*
Y-358316D01*
Y-358284D01*
Y-358252D01*
Y-358219D01*
Y-358187D01*
Y-358155D01*
Y-358122D01*
Y-358090D01*
Y-358058D01*
Y-358026D01*
Y-357993D01*
Y-357961D01*
Y-357929D01*
Y-357897D01*
Y-357864D01*
Y-357832D01*
Y-357800D01*
Y-357768D01*
Y-357735D01*
Y-357703D01*
Y-357671D01*
Y-357639D01*
Y-357606D01*
Y-357574D01*
Y-357542D01*
Y-357509D01*
Y-357477D01*
Y-357445D01*
Y-357413D01*
Y-357380D01*
Y-357348D01*
Y-357316D01*
Y-357284D01*
Y-357251D01*
Y-357219D01*
Y-357187D01*
Y-357155D01*
Y-357122D01*
Y-357090D01*
Y-357058D01*
Y-357026D01*
Y-356993D01*
Y-356961D01*
Y-356929D01*
Y-356896D01*
Y-356864D01*
Y-356832D01*
D01*
Y-356800D01*
Y-356768D01*
Y-356735D01*
Y-356703D01*
Y-356671D01*
Y-356638D01*
Y-356606D01*
Y-356574D01*
Y-356542D01*
Y-356509D01*
Y-356477D01*
Y-356445D01*
Y-356413D01*
Y-356380D01*
Y-356348D01*
Y-356316D01*
Y-356283D01*
Y-356251D01*
Y-356219D01*
Y-356187D01*
Y-356154D01*
Y-356122D01*
Y-356090D01*
Y-356058D01*
Y-356025D01*
Y-355993D01*
Y-355961D01*
X366870Y-355945D01*
X366869Y-355929D01*
Y-355896D01*
Y-355864D01*
Y-355832D01*
Y-355800D01*
Y-355795D01*
X366868Y-355792D01*
X366865Y-355784D01*
X366859Y-355774D01*
X366835Y-355727D01*
X366834Y-355723D01*
X366833Y-355719D01*
X366826Y-355710D01*
X366821Y-355698D01*
X366812Y-355680D01*
X366810Y-355679D01*
X366809Y-355677D01*
X366780Y-355663D01*
X366770Y-355657D01*
X366762Y-355654D01*
X366742Y-355644D01*
X366715Y-355638D01*
X366690Y-355630D01*
X366664Y-355638D01*
X366638Y-355644D01*
X366638D01*
X366617Y-355654D01*
X366609Y-355657D01*
X366600Y-355663D01*
X366570Y-355677D01*
X366569Y-355679D01*
X366554Y-355696D01*
X366536Y-355711D01*
X366535Y-355713D01*
X366521Y-355742D01*
X366514Y-355751D01*
X366512Y-355759D01*
X366510Y-355763D01*
Y-355767D01*
Y-355800D01*
X366509Y-355816D01*
X366510Y-355832D01*
Y-355864D01*
Y-355896D01*
X366509Y-355912D01*
X366510Y-355929D01*
Y-355961D01*
Y-355993D01*
Y-356025D01*
Y-356058D01*
Y-356090D01*
Y-356122D01*
Y-356154D01*
Y-356187D01*
Y-356219D01*
Y-356251D01*
Y-356283D01*
Y-356316D01*
Y-356348D01*
Y-356380D01*
Y-356413D01*
Y-356445D01*
Y-356477D01*
Y-356509D01*
Y-356542D01*
Y-356574D01*
Y-356606D01*
Y-356638D01*
Y-356671D01*
Y-356703D01*
Y-356735D01*
Y-356768D01*
Y-356800D01*
Y-356832D01*
D01*
Y-356864D01*
Y-356896D01*
Y-356929D01*
Y-356961D01*
Y-356993D01*
Y-357026D01*
Y-357058D01*
Y-357090D01*
Y-357122D01*
Y-357155D01*
Y-357187D01*
Y-357219D01*
Y-357251D01*
Y-357284D01*
Y-357316D01*
X366506Y-357368D01*
X366496Y-357420D01*
X366479Y-357469D01*
X366475Y-357477D01*
X366474Y-357497D01*
X366464Y-357549D01*
X366447Y-357598D01*
X366424Y-357645D01*
X366395Y-357689D01*
X366360Y-357728D01*
X366343Y-357744D01*
X366328Y-357761D01*
X366311Y-357776D01*
X366296Y-357793D01*
X366278Y-357808D01*
X366263Y-357825D01*
X366246Y-357840D01*
X366231Y-357857D01*
X366192Y-357892D01*
X366148Y-357921D01*
X366101Y-357944D01*
X366051Y-357961D01*
X366025Y-357966D01*
X366004Y-357977D01*
X365955Y-357994D01*
X365903Y-358004D01*
X365851Y-358007D01*
X363915D01*
X363863Y-358004D01*
X363811Y-357994D01*
X363762Y-357977D01*
X363741Y-357966D01*
X363715Y-357961D01*
X363665Y-357944D01*
X363618Y-357921D01*
X363574Y-357892D01*
X363535Y-357857D01*
X363520Y-357840D01*
X363503Y-357825D01*
X363488Y-357808D01*
X363470Y-357793D01*
X363455Y-357776D01*
X363438Y-357761D01*
X363431Y-357752D01*
X363423Y-357744D01*
X363406Y-357728D01*
X363371Y-357689D01*
X363342Y-357645D01*
X363319Y-357598D01*
X363302Y-357549D01*
X363297Y-357522D01*
X363287Y-357502D01*
X363270Y-357452D01*
X363260Y-357400D01*
X363256Y-357348D01*
Y-357316D01*
Y-357284D01*
Y-357251D01*
Y-357219D01*
Y-357187D01*
Y-357155D01*
Y-357122D01*
Y-357090D01*
Y-357058D01*
Y-357026D01*
Y-356993D01*
Y-356961D01*
Y-356929D01*
Y-356896D01*
Y-356864D01*
Y-356832D01*
D01*
Y-356800D01*
Y-356768D01*
Y-356735D01*
Y-356703D01*
Y-356671D01*
Y-356638D01*
Y-356606D01*
Y-356574D01*
Y-356542D01*
Y-356509D01*
Y-356477D01*
Y-356445D01*
Y-356413D01*
Y-356380D01*
Y-356348D01*
Y-356316D01*
Y-356283D01*
Y-356251D01*
Y-356219D01*
Y-356187D01*
Y-356154D01*
Y-356122D01*
Y-356090D01*
Y-356058D01*
Y-356025D01*
Y-355993D01*
Y-355961D01*
Y-355929D01*
Y-355896D01*
Y-355864D01*
Y-355832D01*
Y-355800D01*
Y-355767D01*
Y-355735D01*
Y-355703D01*
X363258Y-355671D01*
X363256Y-355638D01*
Y-355620D01*
X358670D01*
Y-355638D01*
Y-355671D01*
Y-355703D01*
Y-355735D01*
Y-355767D01*
Y-355800D01*
Y-355832D01*
Y-355864D01*
Y-355896D01*
Y-355929D01*
Y-355961D01*
Y-355993D01*
Y-356025D01*
Y-356058D01*
Y-356090D01*
Y-356122D01*
Y-356154D01*
Y-356187D01*
Y-356219D01*
Y-356251D01*
Y-356283D01*
Y-356316D01*
Y-356348D01*
Y-356380D01*
Y-356413D01*
Y-356445D01*
Y-356477D01*
Y-356509D01*
Y-356542D01*
Y-356574D01*
Y-356606D01*
Y-356638D01*
Y-356671D01*
Y-356703D01*
Y-356735D01*
Y-356768D01*
Y-356800D01*
Y-356832D01*
D01*
Y-356864D01*
Y-356896D01*
Y-356929D01*
Y-356961D01*
Y-356993D01*
Y-357026D01*
Y-357058D01*
Y-357090D01*
Y-357122D01*
Y-357155D01*
Y-357187D01*
Y-357219D01*
Y-357251D01*
Y-357284D01*
Y-357316D01*
Y-357348D01*
Y-357380D01*
Y-357413D01*
Y-357445D01*
Y-357477D01*
Y-357509D01*
Y-357542D01*
Y-357574D01*
Y-357606D01*
Y-357639D01*
Y-357671D01*
Y-357703D01*
Y-357735D01*
Y-357768D01*
Y-357800D01*
Y-357832D01*
Y-357864D01*
Y-357897D01*
Y-357929D01*
Y-357961D01*
Y-357993D01*
Y-358026D01*
Y-358058D01*
Y-358090D01*
Y-358122D01*
Y-358155D01*
Y-358187D01*
Y-358219D01*
X358667Y-358272D01*
X358657Y-358323D01*
X358640Y-358373D01*
X358616Y-358420D01*
X358587Y-358463D01*
X358553Y-358503D01*
X358513Y-358537D01*
X358470Y-358566D01*
X358423Y-358590D01*
X358373Y-358606D01*
X358322Y-358617D01*
X358269Y-358620D01*
X353462D01*
X353410Y-358617D01*
X353359Y-358606D01*
X353309Y-358590D01*
X353262Y-358566D01*
X353218Y-358537D01*
X353179Y-358503D01*
X353144Y-358463D01*
X353115Y-358420D01*
X353092Y-358373D01*
X353075Y-358323D01*
X353065Y-358272D01*
X353061Y-358219D01*
Y-358187D01*
Y-358155D01*
Y-358122D01*
Y-358090D01*
Y-358058D01*
Y-358026D01*
Y-357993D01*
Y-357961D01*
Y-357929D01*
Y-357897D01*
Y-357864D01*
Y-357832D01*
Y-357800D01*
Y-357768D01*
Y-357735D01*
Y-357703D01*
Y-357671D01*
Y-357639D01*
Y-357606D01*
Y-357574D01*
Y-357542D01*
Y-357509D01*
Y-357477D01*
Y-357445D01*
Y-357413D01*
Y-357380D01*
Y-357348D01*
Y-357316D01*
Y-357284D01*
Y-357251D01*
Y-357219D01*
Y-357187D01*
Y-357155D01*
Y-357122D01*
Y-357090D01*
Y-357058D01*
Y-357026D01*
Y-356993D01*
Y-356961D01*
Y-356929D01*
Y-356896D01*
Y-356864D01*
Y-356832D01*
D01*
Y-356800D01*
Y-356768D01*
Y-356735D01*
Y-356703D01*
Y-356671D01*
Y-356638D01*
Y-356606D01*
Y-356574D01*
Y-356542D01*
Y-356509D01*
Y-356477D01*
Y-356445D01*
Y-356413D01*
Y-356380D01*
Y-356348D01*
Y-356316D01*
Y-356283D01*
Y-356251D01*
Y-356219D01*
Y-356187D01*
Y-356154D01*
Y-356122D01*
Y-356090D01*
Y-356058D01*
Y-356025D01*
Y-355993D01*
Y-355961D01*
Y-355929D01*
Y-355896D01*
Y-355864D01*
Y-355832D01*
Y-355800D01*
Y-355767D01*
Y-355735D01*
Y-355703D01*
Y-355671D01*
Y-355638D01*
Y-355606D01*
Y-355574D01*
Y-355541D01*
Y-355509D01*
Y-355477D01*
Y-355445D01*
Y-355413D01*
Y-355380D01*
Y-355348D01*
Y-355316D01*
X353065Y-355263D01*
X353075Y-355212D01*
X353092Y-355162D01*
X353115Y-355115D01*
X353144Y-355072D01*
X353179Y-355032D01*
X353218Y-354998D01*
X353262Y-354969D01*
X353309Y-354945D01*
X353359Y-354928D01*
X353410Y-354918D01*
X353462Y-354915D01*
X353930D01*
X353896Y-354892D01*
X353856Y-354857D01*
X353841Y-354840D01*
X353840Y-354838D01*
X353810Y-354824D01*
X353767Y-354795D01*
X353727Y-354760D01*
X353712Y-354743D01*
X353695Y-354728D01*
X353680Y-354711D01*
X353663Y-354696D01*
X353648Y-354679D01*
X353630Y-354663D01*
X353615Y-354646D01*
X353598Y-354631D01*
X353583Y-354614D01*
X353566Y-354599D01*
X353531Y-354560D01*
X353502Y-354516D01*
X353488Y-354487D01*
X353467Y-354463D01*
X353438Y-354419D01*
X353415Y-354372D01*
X353412Y-354364D01*
X353405Y-354355D01*
X353382Y-354308D01*
X353380Y-354300D01*
X353373Y-354290D01*
X353350Y-354243D01*
X353347Y-354235D01*
X353341Y-354226D01*
X353318Y-354179D01*
X353315Y-354171D01*
X353309Y-354161D01*
X353286Y-354114D01*
X353269Y-354064D01*
X353265Y-354045D01*
X353263Y-354038D01*
X353253Y-354017D01*
X353236Y-353968D01*
X353226Y-353916D01*
X353223Y-353864D01*
Y-353859D01*
X353221Y-353856D01*
X353204Y-353806D01*
X353194Y-353755D01*
X353190Y-353703D01*
Y-353670D01*
Y-353638D01*
Y-353606D01*
Y-353573D01*
Y-353541D01*
Y-353509D01*
Y-353477D01*
Y-353445D01*
Y-353412D01*
Y-353380D01*
X353194Y-353328D01*
X353204Y-353276D01*
X353221Y-353227D01*
X353223Y-353223D01*
Y-353219D01*
X353226Y-353166D01*
X353236Y-353115D01*
X353253Y-353065D01*
X353263Y-353045D01*
X353269Y-353018D01*
X353286Y-352969D01*
X353309Y-352921D01*
X353315Y-352912D01*
X353318Y-352904D01*
X353341Y-352857D01*
X353347Y-352847D01*
X353350Y-352839D01*
X353373Y-352792D01*
X353380Y-352783D01*
X353382Y-352775D01*
X353405Y-352728D01*
X353412Y-352718D01*
X353415Y-352710D01*
X353438Y-352663D01*
X353467Y-352620D01*
X353479Y-352606D01*
X353488Y-352596D01*
X353502Y-352567D01*
X353531Y-352523D01*
X353566Y-352484D01*
X353583Y-352468D01*
X353598Y-352451D01*
X353615Y-352436D01*
X353630Y-352419D01*
X353648Y-352404D01*
X353663Y-352387D01*
X353680Y-352372D01*
X353695Y-352355D01*
X353712Y-352340D01*
X353727Y-352322D01*
X353745Y-352307D01*
X353760Y-352290D01*
X353799Y-352255D01*
X353843Y-352226D01*
X353872Y-352212D01*
X353896Y-352191D01*
X353930Y-352168D01*
X353462D01*
X353410Y-352164D01*
X353359Y-352154D01*
X353309Y-352137D01*
X353262Y-352114D01*
X353218Y-352085D01*
X353179Y-352050D01*
X353144Y-352011D01*
X353115Y-351967D01*
X353092Y-351920D01*
X353075Y-351871D01*
X353065Y-351819D01*
X353061Y-351767D01*
Y-351735D01*
Y-351702D01*
Y-351670D01*
Y-351638D01*
Y-351606D01*
Y-351573D01*
Y-351541D01*
Y-351509D01*
Y-351477D01*
Y-351444D01*
Y-351412D01*
Y-351380D01*
Y-351347D01*
Y-351315D01*
Y-351283D01*
Y-351251D01*
Y-351218D01*
Y-351186D01*
Y-351154D01*
Y-351122D01*
Y-351089D01*
Y-351057D01*
Y-351025D01*
Y-350993D01*
Y-350960D01*
X353065Y-350908D01*
X353075Y-350857D01*
X353092Y-350807D01*
X353115Y-350760D01*
X353144Y-350716D01*
X353179Y-350677D01*
X353218Y-350642D01*
X353262Y-350613D01*
X353309Y-350590D01*
X353359Y-350573D01*
X353410Y-350563D01*
X353462Y-350559D01*
X353963D01*
X353962Y-350559D01*
X353954Y-350556D01*
X353907Y-350533D01*
X353864Y-350504D01*
X353824Y-350469D01*
X353809Y-350452D01*
X353807Y-350451D01*
X353778Y-350436D01*
X353734Y-350407D01*
X353695Y-350373D01*
X353685Y-350361D01*
X353680Y-350356D01*
X353663Y-350341D01*
X353648Y-350323D01*
X353630Y-350308D01*
X353615Y-350291D01*
X353598Y-350276D01*
X353564Y-350237D01*
X353535Y-350193D01*
X353520Y-350164D01*
X353519Y-350162D01*
X353502Y-350147D01*
X353467Y-350108D01*
X353438Y-350064D01*
X353415Y-350017D01*
X353412Y-350009D01*
X353405Y-349999D01*
X353382Y-349952D01*
X353380Y-349944D01*
X353373Y-349935D01*
X353350Y-349888D01*
X353347Y-349880D01*
X353341Y-349870D01*
X353318Y-349823D01*
X353315Y-349815D01*
X353309Y-349806D01*
X353286Y-349759D01*
X353269Y-349709D01*
X353263Y-349682D01*
X353253Y-349662D01*
X353236Y-349612D01*
X353226Y-349561D01*
X353223Y-349509D01*
Y-349504D01*
X353221Y-349501D01*
X353204Y-349451D01*
X353194Y-349400D01*
X353190Y-349347D01*
Y-349315D01*
Y-349283D01*
Y-349251D01*
Y-349218D01*
Y-349186D01*
Y-349154D01*
Y-349121D01*
Y-349089D01*
Y-349057D01*
Y-349025D01*
X353194Y-348972D01*
X353204Y-348921D01*
X353221Y-348871D01*
X353223Y-348868D01*
Y-348863D01*
X353226Y-348811D01*
X353236Y-348760D01*
X353253Y-348710D01*
X353254Y-348709D01*
X353263Y-348689D01*
X353269Y-348663D01*
X353286Y-348613D01*
X353296Y-348593D01*
X353301Y-348566D01*
X353318Y-348516D01*
X353341Y-348469D01*
X353347Y-348460D01*
X353350Y-348452D01*
X353373Y-348405D01*
X353380Y-348395D01*
X353382Y-348387D01*
X353405Y-348340D01*
X353435Y-348297D01*
X353455Y-348273D01*
X353470Y-348243D01*
X353499Y-348200D01*
X353534Y-348161D01*
X353551Y-348145D01*
X353566Y-348128D01*
X353583Y-348113D01*
X353598Y-348096D01*
X353615Y-348081D01*
X353630Y-348064D01*
X353648Y-348049D01*
X353663Y-348031D01*
X353680Y-348016D01*
X353695Y-347999D01*
X353712Y-347984D01*
X353727Y-347967D01*
X353745Y-347952D01*
X353760Y-347935D01*
X353777Y-347920D01*
X353792Y-347902D01*
X353831Y-347868D01*
X353875Y-347839D01*
X353922Y-347815D01*
X353930Y-347813D01*
X353930Y-347812D01*
X353495D01*
X353442Y-347809D01*
X353391Y-347799D01*
X353341Y-347782D01*
X353294Y-347759D01*
X353251Y-347730D01*
X353211Y-347695D01*
X353210Y-347694D01*
X353196Y-347678D01*
X353179Y-347663D01*
X353144Y-347623D01*
X353115Y-347580D01*
X353092Y-347533D01*
X353075Y-347483D01*
X353065Y-347432D01*
X353061Y-347379D01*
Y-347347D01*
Y-347315D01*
Y-347283D01*
Y-347250D01*
Y-347218D01*
Y-347186D01*
Y-347153D01*
Y-347121D01*
Y-347089D01*
Y-347057D01*
Y-347024D01*
Y-346992D01*
Y-346960D01*
Y-346928D01*
Y-346895D01*
Y-346863D01*
Y-346831D01*
Y-346799D01*
Y-346766D01*
Y-346734D01*
Y-346702D01*
Y-346670D01*
Y-346637D01*
Y-346605D01*
X353065Y-346553D01*
X353075Y-346501D01*
X353092Y-346452D01*
X353115Y-346405D01*
X353144Y-346361D01*
X353179Y-346322D01*
X353218Y-346287D01*
X353262Y-346258D01*
X353309Y-346235D01*
X353359Y-346218D01*
X353410Y-346208D01*
X353462Y-346204D01*
X353963D01*
X353928Y-346181D01*
X353904Y-346160D01*
X353875Y-346146D01*
X353831Y-346116D01*
X353792Y-346082D01*
X353777Y-346065D01*
X353760Y-346050D01*
X353759Y-346049D01*
X353745Y-346033D01*
X353727Y-346017D01*
X353712Y-346000D01*
X353695Y-345985D01*
X353680Y-345968D01*
X353663Y-345953D01*
X353648Y-345936D01*
X353630Y-345921D01*
X353615Y-345903D01*
X353598Y-345888D01*
X353583Y-345871D01*
X353566Y-345856D01*
X353551Y-345839D01*
X353534Y-345824D01*
X353499Y-345784D01*
X353470Y-345741D01*
X353455Y-345711D01*
X353435Y-345688D01*
X353405Y-345644D01*
X353382Y-345597D01*
X353380Y-345589D01*
X353373Y-345580D01*
X353350Y-345532D01*
X353347Y-345524D01*
X353341Y-345515D01*
X353318Y-345468D01*
X353301Y-345418D01*
X353296Y-345392D01*
X353286Y-345371D01*
X353269Y-345321D01*
X353263Y-345295D01*
X353253Y-345274D01*
X353236Y-345225D01*
X353226Y-345173D01*
X353225Y-345153D01*
X353221Y-345145D01*
X353204Y-345096D01*
X353194Y-345044D01*
X353190Y-344992D01*
Y-344960D01*
Y-344927D01*
Y-344895D01*
Y-344863D01*
Y-344831D01*
Y-344798D01*
Y-344766D01*
Y-344734D01*
Y-344702D01*
Y-344669D01*
Y-344637D01*
X353194Y-344585D01*
X353204Y-344533D01*
X353221Y-344484D01*
X353225Y-344476D01*
X353226Y-344456D01*
X353236Y-344404D01*
X353253Y-344355D01*
X353257Y-344347D01*
X353258Y-344327D01*
X353269Y-344275D01*
X353286Y-344226D01*
X353309Y-344179D01*
X353315Y-344169D01*
X353318Y-344161D01*
X353341Y-344114D01*
X353346Y-344107D01*
X353347Y-344105D01*
X353350Y-344096D01*
X353373Y-344049D01*
X353380Y-344040D01*
X353382Y-344032D01*
X353405Y-343985D01*
X353435Y-343941D01*
X353453Y-343920D01*
X353455Y-343917D01*
X353470Y-343888D01*
X353499Y-343845D01*
X353534Y-343805D01*
X353551Y-343790D01*
X353566Y-343773D01*
X353583Y-343758D01*
X353598Y-343741D01*
X353615Y-343725D01*
X353630Y-343708D01*
X353648Y-343693D01*
X353663Y-343676D01*
X353680Y-343661D01*
X353695Y-343644D01*
X353712Y-343629D01*
X353727Y-343612D01*
X353745Y-343596D01*
X353760Y-343579D01*
X353776Y-343565D01*
X353777Y-343564D01*
X353792Y-343547D01*
X353831Y-343513D01*
X353875Y-343483D01*
X353904Y-343469D01*
X353928Y-343448D01*
X353963Y-343425D01*
X353462D01*
X353410Y-343421D01*
X353359Y-343411D01*
X353309Y-343394D01*
X353262Y-343371D01*
X353218Y-343342D01*
X353179Y-343307D01*
X353144Y-343268D01*
X353115Y-343224D01*
X353092Y-343177D01*
X353075Y-343128D01*
X353065Y-343076D01*
X353061Y-343024D01*
Y-342992D01*
Y-342959D01*
Y-342927D01*
Y-342895D01*
Y-342863D01*
Y-342830D01*
Y-342798D01*
Y-342766D01*
Y-342734D01*
Y-342701D01*
Y-342669D01*
Y-342637D01*
Y-342604D01*
Y-342572D01*
Y-342540D01*
Y-342508D01*
Y-342476D01*
Y-342443D01*
Y-342411D01*
Y-342379D01*
Y-342346D01*
Y-342314D01*
Y-342282D01*
Y-342250D01*
X353065Y-342197D01*
X353075Y-342146D01*
X353092Y-342096D01*
X353115Y-342049D01*
X353144Y-342006D01*
X353179Y-341966D01*
X353195Y-341952D01*
X353196Y-341951D01*
X353211Y-341934D01*
X353251Y-341899D01*
X353294Y-341870D01*
X353341Y-341847D01*
X353391Y-341830D01*
X353442Y-341820D01*
X353495Y-341816D01*
X353930D01*
X353896Y-341793D01*
X353872Y-341773D01*
X353843Y-341758D01*
X353799Y-341729D01*
X353760Y-341694D01*
X353744Y-341677D01*
X353727Y-341662D01*
X353712Y-341645D01*
X353695Y-341630D01*
X353680Y-341613D01*
X353663Y-341598D01*
X353648Y-341580D01*
X353630Y-341565D01*
X353615Y-341548D01*
X353598Y-341533D01*
X353583Y-341516D01*
X353566Y-341501D01*
X353551Y-341484D01*
X353534Y-341469D01*
X353499Y-341429D01*
X353470Y-341385D01*
X353447Y-341338D01*
X353444Y-341330D01*
X353438Y-341321D01*
X353423Y-341292D01*
X353402Y-341268D01*
X353373Y-341224D01*
X353350Y-341177D01*
X353347Y-341169D01*
X353341Y-341160D01*
X353318Y-341113D01*
X353301Y-341063D01*
X353296Y-341036D01*
X353286Y-341016D01*
X353269Y-340966D01*
X353263Y-340939D01*
X353253Y-340919D01*
X353236Y-340869D01*
X353226Y-340818D01*
X353223Y-340766D01*
Y-340761D01*
X353221Y-340758D01*
X353204Y-340708D01*
X353194Y-340657D01*
X353190Y-340604D01*
Y-340572D01*
Y-340540D01*
Y-340508D01*
Y-340475D01*
Y-340443D01*
Y-340411D01*
Y-340378D01*
Y-340346D01*
Y-340314D01*
Y-340282D01*
X353194Y-340229D01*
X353204Y-340178D01*
X353221Y-340128D01*
X353223Y-340125D01*
Y-340120D01*
X353226Y-340068D01*
X353236Y-340017D01*
X353253Y-339967D01*
X353263Y-339947D01*
X353269Y-339920D01*
X353286Y-339870D01*
X353309Y-339823D01*
X353315Y-339814D01*
X353318Y-339806D01*
X353341Y-339759D01*
X353347Y-339749D01*
X353350Y-339741D01*
X353373Y-339694D01*
X353380Y-339685D01*
X353382Y-339677D01*
X353405Y-339630D01*
X353412Y-339620D01*
X353415Y-339612D01*
X353438Y-339565D01*
X353467Y-339522D01*
X353502Y-339482D01*
X353519Y-339467D01*
X353520Y-339465D01*
X353535Y-339436D01*
X353564Y-339392D01*
X353598Y-339353D01*
X353615Y-339338D01*
X353630Y-339321D01*
X353648Y-339306D01*
X353663Y-339288D01*
X353680Y-339273D01*
X353695Y-339256D01*
X353734Y-339222D01*
X353778Y-339193D01*
X353807Y-339178D01*
X353809Y-339177D01*
X353824Y-339159D01*
X353864Y-339125D01*
X353907Y-339096D01*
X353936Y-339081D01*
X353950Y-339070D01*
X353462D01*
X353410Y-339066D01*
X353359Y-339056D01*
X353309Y-339039D01*
X353262Y-339016D01*
X353218Y-338987D01*
X353179Y-338952D01*
X353144Y-338913D01*
X353115Y-338869D01*
X353092Y-338822D01*
X353075Y-338772D01*
X353065Y-338721D01*
X353061Y-338669D01*
Y-338636D01*
Y-338604D01*
Y-338572D01*
Y-338540D01*
Y-338507D01*
Y-338475D01*
Y-338443D01*
Y-338410D01*
Y-338378D01*
Y-338346D01*
Y-338314D01*
Y-338281D01*
Y-338249D01*
Y-338217D01*
Y-338185D01*
Y-338152D01*
Y-338120D01*
Y-338088D01*
Y-338056D01*
D01*
Y-338023D01*
Y-337991D01*
Y-337959D01*
Y-337927D01*
Y-337894D01*
Y-337862D01*
Y-337830D01*
Y-337797D01*
Y-337765D01*
Y-337733D01*
Y-337701D01*
Y-337668D01*
Y-337636D01*
Y-337604D01*
Y-337572D01*
Y-337539D01*
Y-337507D01*
Y-337475D01*
Y-337443D01*
Y-337410D01*
Y-337378D01*
Y-337346D01*
Y-337314D01*
Y-337281D01*
Y-337249D01*
Y-337217D01*
Y-337185D01*
Y-337152D01*
Y-337120D01*
Y-337088D01*
Y-337055D01*
Y-337023D01*
Y-336991D01*
Y-336959D01*
Y-336927D01*
Y-336894D01*
Y-336862D01*
Y-336830D01*
Y-336797D01*
Y-336765D01*
Y-336733D01*
Y-336701D01*
Y-336668D01*
Y-336636D01*
Y-336604D01*
Y-336572D01*
Y-336539D01*
Y-336507D01*
Y-336475D01*
Y-336442D01*
Y-336410D01*
Y-336378D01*
Y-336346D01*
Y-336314D01*
Y-336281D01*
Y-336249D01*
Y-336217D01*
Y-336184D01*
Y-336152D01*
Y-336120D01*
Y-336088D01*
Y-336055D01*
Y-336023D01*
Y-335991D01*
Y-335959D01*
Y-335926D01*
Y-335894D01*
Y-335862D01*
Y-335830D01*
Y-335797D01*
Y-335765D01*
Y-335733D01*
Y-335700D01*
Y-335668D01*
Y-335636D01*
Y-335604D01*
Y-335572D01*
Y-335539D01*
Y-335507D01*
Y-335475D01*
Y-335442D01*
Y-335410D01*
Y-335378D01*
Y-335346D01*
Y-335313D01*
Y-335281D01*
Y-335249D01*
Y-335217D01*
Y-335184D01*
Y-335152D01*
Y-335120D01*
Y-335087D01*
Y-335055D01*
Y-335023D01*
Y-334991D01*
Y-334959D01*
Y-334926D01*
Y-334894D01*
Y-334862D01*
Y-334829D01*
Y-334797D01*
Y-334765D01*
Y-334733D01*
Y-334700D01*
Y-334668D01*
Y-334636D01*
Y-334604D01*
Y-334571D01*
Y-334539D01*
Y-334507D01*
Y-334474D01*
Y-334442D01*
Y-334410D01*
Y-334378D01*
Y-334346D01*
Y-334313D01*
Y-334281D01*
Y-334249D01*
Y-334216D01*
Y-334184D01*
Y-334152D01*
Y-334120D01*
Y-334087D01*
Y-334055D01*
Y-334023D01*
Y-333991D01*
D01*
Y-333958D01*
Y-333926D01*
Y-333894D01*
Y-333862D01*
Y-333829D01*
Y-333797D01*
Y-333765D01*
Y-333733D01*
Y-333700D01*
Y-333668D01*
Y-333636D01*
Y-333604D01*
Y-333571D01*
Y-333539D01*
Y-333507D01*
Y-333474D01*
Y-333442D01*
Y-333410D01*
Y-333378D01*
Y-333345D01*
Y-333313D01*
Y-333281D01*
Y-333249D01*
Y-333216D01*
Y-333184D01*
Y-333152D01*
Y-333120D01*
Y-333087D01*
Y-333055D01*
Y-333023D01*
Y-332991D01*
Y-332958D01*
Y-332926D01*
Y-332894D01*
Y-332861D01*
Y-332829D01*
Y-332797D01*
Y-332765D01*
Y-332732D01*
Y-332700D01*
Y-332668D01*
Y-332636D01*
Y-332603D01*
Y-332571D01*
Y-332539D01*
Y-332507D01*
Y-332474D01*
Y-332442D01*
Y-332410D01*
Y-332378D01*
Y-332345D01*
Y-332313D01*
Y-332281D01*
Y-332248D01*
Y-332216D01*
Y-332184D01*
Y-332152D01*
Y-332119D01*
Y-332087D01*
Y-332055D01*
Y-332023D01*
Y-331990D01*
Y-331958D01*
Y-331926D01*
Y-331894D01*
Y-331861D01*
Y-331829D01*
Y-331797D01*
Y-331765D01*
Y-331732D01*
Y-331700D01*
Y-331668D01*
Y-331635D01*
Y-331603D01*
Y-331571D01*
Y-331539D01*
Y-331506D01*
Y-331474D01*
Y-331442D01*
Y-331410D01*
Y-331377D01*
Y-331345D01*
Y-331313D01*
Y-331281D01*
Y-331248D01*
Y-331216D01*
Y-331184D01*
Y-331152D01*
Y-331119D01*
Y-331087D01*
Y-331055D01*
Y-331023D01*
Y-330990D01*
Y-330958D01*
Y-330926D01*
Y-330893D01*
Y-330861D01*
Y-330829D01*
Y-330797D01*
Y-330764D01*
Y-330732D01*
Y-330700D01*
Y-330668D01*
Y-330635D01*
Y-330603D01*
Y-330571D01*
Y-330539D01*
Y-330506D01*
Y-330474D01*
Y-330442D01*
Y-330410D01*
Y-330377D01*
Y-330345D01*
Y-330313D01*
Y-330280D01*
Y-330248D01*
Y-330216D01*
Y-330184D01*
Y-330152D01*
Y-330119D01*
Y-330087D01*
Y-330055D01*
Y-330022D01*
Y-329990D01*
Y-329958D01*
Y-329926D01*
Y-329893D01*
Y-329861D01*
Y-329829D01*
Y-329797D01*
Y-329764D01*
Y-329732D01*
Y-329700D01*
Y-329667D01*
Y-329635D01*
Y-329603D01*
Y-329571D01*
Y-329538D01*
Y-329506D01*
Y-329474D01*
Y-329442D01*
Y-329410D01*
Y-329377D01*
Y-329345D01*
Y-329313D01*
Y-329280D01*
Y-329248D01*
Y-329216D01*
Y-329184D01*
Y-329151D01*
Y-329119D01*
Y-329087D01*
Y-329055D01*
Y-329022D01*
Y-328990D01*
Y-328958D01*
Y-328925D01*
Y-328893D01*
Y-328861D01*
Y-328829D01*
Y-328797D01*
Y-328764D01*
Y-328732D01*
Y-328700D01*
Y-328667D01*
Y-328635D01*
Y-328603D01*
Y-328571D01*
Y-328538D01*
Y-328506D01*
Y-328474D01*
Y-328442D01*
Y-328409D01*
Y-328377D01*
Y-328345D01*
Y-328313D01*
Y-328280D01*
Y-328248D01*
Y-328216D01*
Y-328184D01*
Y-328151D01*
Y-328119D01*
Y-328087D01*
Y-328054D01*
Y-328022D01*
Y-327990D01*
Y-327958D01*
Y-327925D01*
Y-327893D01*
Y-327861D01*
Y-327829D01*
Y-327796D01*
Y-327764D01*
Y-327732D01*
Y-327700D01*
Y-327667D01*
Y-327635D01*
Y-327603D01*
Y-327571D01*
Y-327538D01*
Y-327506D01*
Y-327474D01*
Y-327442D01*
Y-327409D01*
Y-327377D01*
Y-327345D01*
Y-327312D01*
Y-327280D01*
Y-327248D01*
Y-327216D01*
Y-327183D01*
Y-327151D01*
Y-327119D01*
Y-327087D01*
Y-327054D01*
Y-327022D01*
Y-326990D01*
Y-326958D01*
Y-326925D01*
Y-326893D01*
Y-326861D01*
Y-326829D01*
Y-326796D01*
Y-326764D01*
Y-326732D01*
Y-326699D01*
Y-326667D01*
Y-326635D01*
Y-326603D01*
Y-326570D01*
Y-326538D01*
Y-326506D01*
Y-326474D01*
Y-326441D01*
Y-326409D01*
Y-326377D01*
Y-326345D01*
Y-326312D01*
Y-326280D01*
Y-326248D01*
Y-326216D01*
Y-326183D01*
Y-326151D01*
Y-326119D01*
Y-326086D01*
Y-326054D01*
Y-326022D01*
Y-325990D01*
Y-325957D01*
Y-325925D01*
Y-325893D01*
Y-325861D01*
Y-325828D01*
Y-325796D01*
X353065Y-325744D01*
X353075Y-325692D01*
X353092Y-325643D01*
X353115Y-325596D01*
X353144Y-325552D01*
X353179Y-325513D01*
X353196Y-325498D01*
X353211Y-325480D01*
X353251Y-325446D01*
X353294Y-325417D01*
X353341Y-325394D01*
X353391Y-325377D01*
X353442Y-325366D01*
X353495Y-325363D01*
X394209D01*
X394261Y-325366D01*
D02*
G37*
G36*
X350417D02*
X350469Y-325377D01*
X350519Y-325394D01*
X350522Y-325395D01*
X350688D01*
X350740Y-325399D01*
X350792Y-325409D01*
X350841Y-325426D01*
X350849Y-325430D01*
X350869Y-325431D01*
X350921Y-325441D01*
X350970Y-325458D01*
X350978Y-325462D01*
X350998Y-325463D01*
X351050Y-325473D01*
X351099Y-325490D01*
X351146Y-325514D01*
X351156Y-325520D01*
X351164Y-325523D01*
X351184Y-325533D01*
X351211Y-325538D01*
X351261Y-325555D01*
X351308Y-325578D01*
X351317Y-325584D01*
X351325Y-325587D01*
X351372Y-325610D01*
X351382Y-325617D01*
X351390Y-325619D01*
X351437Y-325643D01*
X351446Y-325649D01*
X351454Y-325652D01*
X351501Y-325675D01*
X351511Y-325681D01*
X351519Y-325684D01*
X351566Y-325707D01*
X351609Y-325736D01*
X351633Y-325757D01*
X351662Y-325772D01*
X351706Y-325801D01*
X351746Y-325835D01*
X351761Y-325852D01*
X351762Y-325854D01*
X351792Y-325868D01*
X351835Y-325898D01*
X351875Y-325932D01*
X351890Y-325949D01*
X351907Y-325964D01*
X351922Y-325981D01*
X351939Y-325997D01*
X351954Y-326014D01*
X351971Y-326029D01*
X351987Y-326046D01*
X352004Y-326061D01*
X352019Y-326078D01*
X352028Y-326086D01*
X352036Y-326093D01*
X352051Y-326111D01*
X352068Y-326126D01*
X352083Y-326143D01*
X352100Y-326158D01*
X352116Y-326175D01*
X352133Y-326190D01*
X352167Y-326230D01*
X352196Y-326273D01*
X352211Y-326303D01*
X352212Y-326304D01*
X352229Y-326319D01*
X352264Y-326359D01*
X352293Y-326402D01*
X352308Y-326432D01*
X352328Y-326455D01*
X352358Y-326499D01*
X352381Y-326546D01*
X352384Y-326554D01*
X352390Y-326564D01*
X352413Y-326611D01*
X352416Y-326619D01*
X352422Y-326628D01*
X352445Y-326675D01*
X352448Y-326683D01*
X352454Y-326693D01*
X352478Y-326740D01*
X352480Y-326748D01*
X352487Y-326757D01*
X352510Y-326804D01*
X352527Y-326854D01*
X352532Y-326881D01*
X352542Y-326901D01*
X352545Y-326909D01*
X352551Y-326918D01*
X352574Y-326965D01*
X352591Y-327015D01*
X352602Y-327067D01*
X352603Y-327087D01*
X352607Y-327095D01*
X352624Y-327144D01*
X352634Y-327196D01*
X352637Y-327248D01*
Y-327252D01*
X352639Y-327256D01*
X352656Y-327306D01*
X352666Y-327357D01*
X352670Y-327409D01*
Y-327442D01*
Y-327474D01*
Y-327506D01*
Y-327538D01*
Y-327571D01*
Y-327603D01*
Y-327635D01*
Y-327667D01*
Y-327700D01*
Y-327732D01*
Y-327764D01*
Y-327796D01*
Y-327829D01*
Y-327861D01*
Y-327893D01*
Y-327925D01*
Y-327958D01*
Y-327990D01*
Y-328022D01*
Y-328054D01*
Y-328087D01*
Y-328119D01*
Y-328151D01*
Y-328184D01*
Y-328216D01*
Y-328248D01*
Y-328280D01*
Y-328313D01*
Y-328345D01*
Y-328377D01*
Y-328409D01*
Y-328442D01*
Y-328474D01*
Y-328506D01*
Y-328538D01*
Y-328571D01*
Y-328603D01*
Y-328635D01*
Y-328667D01*
Y-328700D01*
Y-328732D01*
Y-328764D01*
Y-328797D01*
Y-328829D01*
Y-328861D01*
Y-328893D01*
Y-328925D01*
Y-328958D01*
Y-328990D01*
Y-329022D01*
Y-329055D01*
Y-329087D01*
Y-329119D01*
Y-329151D01*
Y-329184D01*
Y-329216D01*
Y-329248D01*
Y-329280D01*
Y-329313D01*
Y-329345D01*
Y-329377D01*
Y-329410D01*
Y-329442D01*
Y-329474D01*
Y-329506D01*
Y-329538D01*
Y-329571D01*
Y-329603D01*
Y-329635D01*
Y-329667D01*
Y-329700D01*
Y-329732D01*
Y-329764D01*
Y-329797D01*
Y-329829D01*
Y-329861D01*
Y-329893D01*
Y-329926D01*
Y-329958D01*
Y-329990D01*
Y-330022D01*
Y-330055D01*
Y-330087D01*
Y-330119D01*
Y-330152D01*
Y-330184D01*
Y-330216D01*
Y-330248D01*
Y-330280D01*
Y-330313D01*
Y-330345D01*
Y-330377D01*
Y-330410D01*
Y-330442D01*
Y-330474D01*
Y-330506D01*
Y-330539D01*
Y-330571D01*
Y-330603D01*
Y-330635D01*
Y-330668D01*
Y-330700D01*
Y-330732D01*
Y-330764D01*
Y-330797D01*
Y-330829D01*
Y-330861D01*
Y-330893D01*
Y-330926D01*
Y-330958D01*
Y-330990D01*
Y-331023D01*
Y-331055D01*
Y-331087D01*
Y-331119D01*
Y-331152D01*
Y-331184D01*
Y-331216D01*
Y-331248D01*
Y-331281D01*
Y-331313D01*
Y-331345D01*
Y-331377D01*
Y-331410D01*
Y-331442D01*
Y-331474D01*
Y-331506D01*
Y-331539D01*
Y-331571D01*
Y-331603D01*
Y-331635D01*
Y-331668D01*
Y-331700D01*
Y-331732D01*
Y-331765D01*
Y-331797D01*
Y-331829D01*
Y-331861D01*
Y-331894D01*
Y-331926D01*
Y-331958D01*
Y-331990D01*
Y-332023D01*
Y-332055D01*
Y-332087D01*
Y-332119D01*
Y-332152D01*
Y-332184D01*
Y-332216D01*
Y-332248D01*
Y-332281D01*
Y-332313D01*
Y-332345D01*
Y-332378D01*
Y-332410D01*
Y-332442D01*
Y-332474D01*
Y-332507D01*
Y-332539D01*
Y-332571D01*
Y-332603D01*
Y-332636D01*
Y-332668D01*
Y-332700D01*
Y-332732D01*
Y-332765D01*
Y-332797D01*
Y-332829D01*
Y-332861D01*
Y-332894D01*
Y-332926D01*
Y-332958D01*
Y-332991D01*
Y-333023D01*
Y-333055D01*
Y-333087D01*
Y-333120D01*
Y-333152D01*
Y-333184D01*
Y-333216D01*
Y-333249D01*
Y-333281D01*
Y-333313D01*
Y-333345D01*
Y-333378D01*
Y-333410D01*
Y-333442D01*
Y-333474D01*
Y-333507D01*
Y-333539D01*
Y-333571D01*
Y-333604D01*
Y-333636D01*
Y-333668D01*
Y-333700D01*
Y-333733D01*
Y-333765D01*
Y-333797D01*
Y-333829D01*
Y-333862D01*
Y-333894D01*
Y-333926D01*
Y-333958D01*
Y-333991D01*
Y-334023D01*
Y-334055D01*
Y-334087D01*
Y-334120D01*
Y-334152D01*
Y-334184D01*
Y-334216D01*
Y-334249D01*
Y-334281D01*
Y-334313D01*
Y-334346D01*
Y-334378D01*
Y-334410D01*
Y-334442D01*
Y-334474D01*
Y-334507D01*
Y-334539D01*
Y-334571D01*
Y-334604D01*
Y-334636D01*
Y-334668D01*
Y-334700D01*
Y-334733D01*
Y-334765D01*
Y-334797D01*
Y-334829D01*
Y-334862D01*
Y-334894D01*
Y-334926D01*
Y-334959D01*
Y-334991D01*
Y-335023D01*
Y-335055D01*
Y-335087D01*
Y-335120D01*
Y-335152D01*
D01*
Y-335184D01*
Y-335217D01*
Y-335249D01*
Y-335281D01*
Y-335313D01*
Y-335346D01*
Y-335378D01*
Y-335410D01*
Y-335442D01*
Y-335475D01*
Y-335507D01*
Y-335539D01*
Y-335572D01*
Y-335604D01*
Y-335636D01*
Y-335668D01*
Y-335700D01*
Y-335733D01*
Y-335765D01*
Y-335797D01*
Y-335830D01*
Y-335862D01*
Y-335894D01*
Y-335926D01*
Y-335959D01*
Y-335991D01*
Y-336023D01*
Y-336055D01*
Y-336088D01*
Y-336120D01*
Y-336152D01*
Y-336184D01*
Y-336217D01*
Y-336249D01*
Y-336281D01*
Y-336314D01*
Y-336346D01*
Y-336378D01*
Y-336410D01*
Y-336442D01*
Y-336475D01*
Y-336507D01*
Y-336539D01*
Y-336572D01*
Y-336604D01*
Y-336636D01*
Y-336668D01*
Y-336701D01*
Y-336733D01*
Y-336765D01*
Y-336797D01*
Y-336830D01*
Y-336862D01*
Y-336894D01*
Y-336927D01*
Y-336959D01*
Y-336991D01*
Y-337023D01*
Y-337055D01*
Y-337088D01*
Y-337120D01*
Y-337152D01*
Y-337185D01*
Y-337217D01*
Y-337249D01*
Y-337281D01*
Y-337314D01*
Y-337346D01*
Y-337378D01*
Y-337410D01*
Y-337443D01*
Y-337475D01*
Y-337507D01*
Y-337539D01*
Y-337572D01*
Y-337604D01*
Y-337636D01*
Y-337668D01*
Y-337701D01*
Y-337733D01*
Y-337765D01*
Y-337797D01*
Y-337830D01*
Y-337862D01*
Y-337894D01*
Y-337927D01*
Y-337959D01*
Y-337991D01*
Y-338023D01*
Y-338056D01*
Y-338088D01*
Y-338120D01*
Y-338152D01*
Y-338185D01*
Y-338217D01*
Y-338249D01*
Y-338281D01*
Y-338314D01*
Y-338346D01*
Y-338378D01*
Y-338410D01*
Y-338443D01*
Y-338475D01*
Y-338507D01*
Y-338540D01*
Y-338572D01*
Y-338604D01*
Y-338636D01*
Y-338669D01*
Y-338701D01*
Y-338733D01*
Y-338765D01*
Y-338798D01*
Y-338830D01*
Y-338862D01*
Y-338894D01*
Y-338927D01*
Y-338959D01*
Y-338991D01*
Y-339023D01*
Y-339056D01*
Y-339088D01*
Y-339120D01*
Y-339153D01*
Y-339185D01*
Y-339217D01*
Y-339249D01*
Y-339282D01*
Y-339314D01*
Y-339346D01*
Y-339378D01*
Y-339411D01*
Y-339443D01*
Y-339475D01*
Y-339507D01*
Y-339540D01*
Y-339572D01*
Y-339604D01*
Y-339636D01*
Y-339669D01*
Y-339701D01*
Y-339733D01*
Y-339766D01*
Y-339798D01*
Y-339830D01*
Y-339862D01*
Y-339895D01*
Y-339927D01*
Y-339959D01*
Y-339991D01*
Y-340024D01*
Y-340056D01*
Y-340088D01*
Y-340120D01*
Y-340153D01*
Y-340185D01*
Y-340217D01*
Y-340249D01*
Y-340282D01*
Y-340314D01*
Y-340346D01*
Y-340378D01*
Y-340411D01*
Y-340443D01*
Y-340475D01*
Y-340508D01*
Y-340540D01*
Y-340572D01*
Y-340604D01*
Y-340637D01*
Y-340669D01*
Y-340701D01*
Y-340733D01*
Y-340766D01*
Y-340798D01*
Y-340830D01*
Y-340862D01*
Y-340895D01*
Y-340927D01*
Y-340959D01*
Y-340991D01*
Y-341024D01*
Y-341056D01*
Y-341088D01*
Y-341121D01*
Y-341153D01*
Y-341185D01*
Y-341217D01*
Y-341249D01*
Y-341282D01*
Y-341314D01*
Y-341346D01*
Y-341379D01*
Y-341411D01*
Y-341443D01*
Y-341475D01*
Y-341508D01*
Y-341540D01*
Y-341572D01*
Y-341604D01*
Y-341637D01*
Y-341669D01*
Y-341701D01*
Y-341734D01*
Y-341766D01*
Y-341798D01*
Y-341830D01*
Y-341863D01*
Y-341895D01*
Y-341927D01*
Y-341959D01*
Y-341992D01*
Y-342024D01*
Y-342056D01*
Y-342088D01*
Y-342121D01*
Y-342153D01*
Y-342185D01*
Y-342217D01*
Y-342250D01*
Y-342282D01*
Y-342314D01*
Y-342346D01*
Y-342379D01*
Y-342411D01*
Y-342443D01*
Y-342476D01*
Y-342508D01*
Y-342540D01*
Y-342572D01*
Y-342604D01*
Y-342637D01*
Y-342669D01*
Y-342701D01*
Y-342734D01*
Y-342766D01*
Y-342798D01*
Y-342830D01*
Y-342863D01*
Y-342895D01*
Y-342927D01*
Y-342959D01*
Y-342992D01*
Y-343024D01*
Y-343056D01*
Y-343089D01*
Y-343121D01*
Y-343153D01*
Y-343185D01*
Y-343217D01*
Y-343250D01*
Y-343282D01*
Y-343314D01*
Y-343347D01*
Y-343379D01*
Y-343411D01*
Y-343443D01*
Y-343476D01*
Y-343508D01*
Y-343540D01*
Y-343572D01*
Y-343605D01*
Y-343637D01*
Y-343669D01*
Y-343701D01*
Y-343734D01*
Y-343766D01*
Y-343798D01*
Y-343830D01*
Y-343863D01*
Y-343895D01*
Y-343927D01*
Y-343959D01*
Y-343992D01*
Y-344024D01*
Y-344056D01*
Y-344089D01*
Y-344121D01*
Y-344153D01*
Y-344185D01*
Y-344218D01*
Y-344250D01*
Y-344282D01*
Y-344314D01*
Y-344347D01*
Y-344379D01*
Y-344411D01*
Y-344443D01*
Y-344476D01*
Y-344508D01*
Y-344540D01*
Y-344572D01*
Y-344605D01*
Y-344637D01*
Y-344669D01*
Y-344702D01*
Y-344734D01*
Y-344766D01*
Y-344798D01*
Y-344831D01*
Y-344863D01*
Y-344895D01*
Y-344927D01*
Y-344960D01*
Y-344992D01*
Y-345024D01*
Y-345056D01*
Y-345089D01*
Y-345121D01*
Y-345153D01*
Y-345185D01*
Y-345218D01*
Y-345250D01*
Y-345282D01*
Y-345315D01*
Y-345347D01*
Y-345379D01*
Y-345411D01*
Y-345444D01*
Y-345476D01*
Y-345508D01*
Y-345540D01*
Y-345573D01*
Y-345605D01*
Y-345637D01*
Y-345669D01*
Y-345702D01*
Y-345734D01*
Y-345766D01*
Y-345798D01*
Y-345831D01*
Y-345863D01*
Y-345895D01*
Y-345928D01*
Y-345960D01*
Y-345992D01*
Y-346024D01*
Y-346057D01*
D01*
Y-346089D01*
Y-346121D01*
Y-346153D01*
Y-346186D01*
Y-346218D01*
Y-346250D01*
Y-346282D01*
Y-346315D01*
Y-346347D01*
Y-346379D01*
Y-346411D01*
Y-346444D01*
Y-346476D01*
Y-346508D01*
Y-346540D01*
Y-346573D01*
Y-346605D01*
Y-346637D01*
Y-346670D01*
Y-346702D01*
Y-346734D01*
Y-346766D01*
Y-346799D01*
Y-346831D01*
Y-346863D01*
Y-346895D01*
Y-346928D01*
Y-346960D01*
Y-346992D01*
Y-347024D01*
Y-347057D01*
Y-347089D01*
Y-347121D01*
Y-347153D01*
Y-347186D01*
Y-347218D01*
Y-347250D01*
Y-347283D01*
Y-347315D01*
Y-347347D01*
Y-347379D01*
Y-347411D01*
Y-347444D01*
Y-347476D01*
Y-347508D01*
Y-347541D01*
Y-347573D01*
Y-347605D01*
Y-347637D01*
Y-347670D01*
Y-347702D01*
Y-347734D01*
Y-347766D01*
Y-347799D01*
Y-347831D01*
Y-347863D01*
Y-347896D01*
Y-347928D01*
Y-347960D01*
Y-347992D01*
Y-348025D01*
Y-348057D01*
Y-348089D01*
Y-348121D01*
Y-348154D01*
Y-348186D01*
Y-348218D01*
Y-348250D01*
Y-348283D01*
Y-348315D01*
Y-348347D01*
Y-348379D01*
Y-348412D01*
Y-348444D01*
Y-348476D01*
Y-348508D01*
Y-348541D01*
Y-348573D01*
Y-348605D01*
Y-348638D01*
Y-348670D01*
Y-348702D01*
Y-348734D01*
Y-348766D01*
Y-348799D01*
Y-348831D01*
Y-348863D01*
Y-348896D01*
Y-348928D01*
Y-348960D01*
Y-348992D01*
Y-349025D01*
Y-349057D01*
Y-349089D01*
Y-349121D01*
Y-349154D01*
Y-349186D01*
Y-349218D01*
Y-349251D01*
Y-349283D01*
Y-349315D01*
Y-349347D01*
Y-349379D01*
Y-349412D01*
Y-349444D01*
Y-349476D01*
Y-349509D01*
Y-349541D01*
Y-349573D01*
Y-349605D01*
Y-349638D01*
Y-349670D01*
Y-349702D01*
Y-349734D01*
Y-349767D01*
Y-349799D01*
Y-349831D01*
Y-349863D01*
Y-349896D01*
Y-349928D01*
Y-349960D01*
Y-349992D01*
Y-350025D01*
Y-350057D01*
Y-350089D01*
Y-350121D01*
Y-350154D01*
Y-350186D01*
Y-350218D01*
Y-350251D01*
Y-350283D01*
Y-350315D01*
Y-350347D01*
Y-350380D01*
Y-350412D01*
Y-350444D01*
Y-350476D01*
Y-350509D01*
Y-350541D01*
Y-350573D01*
Y-350606D01*
Y-350638D01*
Y-350670D01*
Y-350702D01*
Y-350734D01*
Y-350767D01*
Y-350799D01*
Y-350831D01*
Y-350864D01*
Y-350896D01*
Y-350928D01*
Y-350960D01*
Y-350993D01*
Y-351025D01*
Y-351057D01*
Y-351089D01*
Y-351122D01*
Y-351154D01*
Y-351186D01*
Y-351218D01*
Y-351251D01*
Y-351283D01*
Y-351315D01*
Y-351347D01*
Y-351380D01*
Y-351412D01*
Y-351444D01*
Y-351477D01*
Y-351509D01*
Y-351541D01*
Y-351573D01*
Y-351606D01*
Y-351638D01*
Y-351670D01*
Y-351702D01*
Y-351735D01*
Y-351767D01*
Y-351799D01*
Y-351831D01*
Y-351864D01*
Y-351896D01*
Y-351928D01*
Y-351960D01*
Y-351993D01*
Y-352025D01*
Y-352057D01*
Y-352090D01*
Y-352122D01*
Y-352154D01*
Y-352186D01*
Y-352219D01*
Y-352251D01*
Y-352283D01*
Y-352315D01*
Y-352348D01*
Y-352380D01*
Y-352412D01*
Y-352444D01*
Y-352477D01*
Y-352509D01*
Y-352541D01*
Y-352573D01*
Y-352606D01*
Y-352638D01*
Y-352670D01*
Y-352702D01*
Y-352735D01*
Y-352767D01*
D01*
Y-352799D01*
Y-352832D01*
Y-352864D01*
Y-352896D01*
Y-352928D01*
Y-352961D01*
Y-352993D01*
Y-353025D01*
Y-353057D01*
Y-353090D01*
Y-353122D01*
Y-353154D01*
Y-353186D01*
Y-353219D01*
Y-353251D01*
Y-353283D01*
Y-353315D01*
Y-353348D01*
Y-353380D01*
Y-353412D01*
Y-353445D01*
Y-353477D01*
Y-353509D01*
Y-353541D01*
Y-353573D01*
Y-353606D01*
Y-353638D01*
Y-353670D01*
Y-353703D01*
Y-353735D01*
Y-353767D01*
Y-353799D01*
Y-353832D01*
Y-353864D01*
Y-353896D01*
Y-353928D01*
Y-353961D01*
Y-353993D01*
Y-354025D01*
Y-354058D01*
Y-354090D01*
Y-354122D01*
Y-354154D01*
Y-354187D01*
Y-354219D01*
Y-354251D01*
Y-354283D01*
Y-354316D01*
Y-354348D01*
Y-354380D01*
Y-354412D01*
Y-354445D01*
Y-354477D01*
Y-354509D01*
Y-354541D01*
Y-354574D01*
Y-354606D01*
Y-354638D01*
Y-354670D01*
Y-354703D01*
Y-354735D01*
Y-354767D01*
Y-354800D01*
Y-354832D01*
Y-354864D01*
Y-354896D01*
Y-354928D01*
Y-354961D01*
Y-354993D01*
Y-355025D01*
Y-355058D01*
Y-355090D01*
Y-355122D01*
Y-355154D01*
Y-355187D01*
Y-355219D01*
Y-355251D01*
Y-355283D01*
Y-355316D01*
Y-355348D01*
Y-355380D01*
Y-355413D01*
Y-355445D01*
Y-355477D01*
Y-355509D01*
Y-355541D01*
Y-355574D01*
Y-355606D01*
Y-355638D01*
Y-355671D01*
Y-355703D01*
Y-355735D01*
Y-355767D01*
Y-355800D01*
Y-355832D01*
Y-355864D01*
Y-355896D01*
Y-355929D01*
Y-355961D01*
Y-355993D01*
Y-356025D01*
Y-356058D01*
Y-356090D01*
Y-356122D01*
Y-356154D01*
Y-356187D01*
Y-356219D01*
Y-356251D01*
Y-356283D01*
Y-356316D01*
Y-356348D01*
Y-356380D01*
Y-356413D01*
Y-356445D01*
Y-356477D01*
Y-356509D01*
Y-356542D01*
Y-356574D01*
Y-356606D01*
Y-356638D01*
Y-356671D01*
Y-356703D01*
Y-356735D01*
Y-356768D01*
Y-356800D01*
Y-356832D01*
Y-356864D01*
Y-356896D01*
Y-356929D01*
Y-356961D01*
Y-356993D01*
Y-357026D01*
Y-357058D01*
Y-357090D01*
Y-357122D01*
Y-357155D01*
Y-357187D01*
Y-357219D01*
Y-357251D01*
Y-357284D01*
Y-357316D01*
Y-357348D01*
Y-357380D01*
Y-357413D01*
Y-357445D01*
Y-357477D01*
Y-357509D01*
Y-357542D01*
Y-357574D01*
Y-357606D01*
Y-357639D01*
Y-357671D01*
Y-357703D01*
Y-357735D01*
Y-357768D01*
Y-357800D01*
Y-357832D01*
Y-357864D01*
Y-357897D01*
Y-357929D01*
Y-357961D01*
Y-357993D01*
Y-358026D01*
Y-358058D01*
Y-358090D01*
Y-358122D01*
Y-358155D01*
Y-358187D01*
Y-358219D01*
Y-358252D01*
Y-358284D01*
Y-358316D01*
Y-358348D01*
Y-358381D01*
Y-358413D01*
Y-358445D01*
Y-358477D01*
Y-358510D01*
Y-358542D01*
Y-358574D01*
Y-358606D01*
Y-358639D01*
Y-358671D01*
Y-358703D01*
Y-358735D01*
Y-358768D01*
Y-358800D01*
Y-358832D01*
Y-358864D01*
Y-358897D01*
Y-358929D01*
Y-358961D01*
Y-358994D01*
Y-359026D01*
Y-359058D01*
Y-359090D01*
Y-359123D01*
Y-359155D01*
Y-359187D01*
Y-359219D01*
Y-359252D01*
Y-359284D01*
Y-359316D01*
Y-359348D01*
Y-359381D01*
Y-359413D01*
Y-359445D01*
Y-359477D01*
Y-359510D01*
Y-359542D01*
Y-359574D01*
Y-359607D01*
Y-359639D01*
Y-359671D01*
Y-359703D01*
Y-359735D01*
Y-359768D01*
Y-359800D01*
Y-359832D01*
Y-359865D01*
Y-359897D01*
Y-359929D01*
Y-359961D01*
Y-359994D01*
Y-360026D01*
Y-360058D01*
Y-360090D01*
Y-360123D01*
Y-360155D01*
Y-360187D01*
Y-360220D01*
Y-360252D01*
Y-360284D01*
Y-360316D01*
Y-360349D01*
Y-360381D01*
Y-360413D01*
Y-360445D01*
Y-360478D01*
Y-360510D01*
Y-360542D01*
Y-360574D01*
Y-360607D01*
Y-360639D01*
Y-360671D01*
Y-360703D01*
Y-360736D01*
Y-360768D01*
Y-360800D01*
Y-360832D01*
Y-360865D01*
Y-360897D01*
Y-360929D01*
Y-360962D01*
Y-360994D01*
Y-361026D01*
Y-361058D01*
Y-361090D01*
Y-361123D01*
Y-361155D01*
Y-361187D01*
Y-361220D01*
Y-361252D01*
Y-361284D01*
Y-361316D01*
Y-361349D01*
Y-361381D01*
Y-361413D01*
Y-361445D01*
Y-361478D01*
Y-361510D01*
Y-361542D01*
Y-361575D01*
Y-361607D01*
Y-361639D01*
Y-361671D01*
Y-361703D01*
Y-361736D01*
Y-361768D01*
Y-361800D01*
Y-361832D01*
Y-361865D01*
Y-361897D01*
Y-361929D01*
Y-361962D01*
Y-361994D01*
Y-362026D01*
Y-362058D01*
Y-362091D01*
Y-362123D01*
Y-362155D01*
Y-362187D01*
Y-362220D01*
Y-362252D01*
Y-362284D01*
Y-362316D01*
Y-362349D01*
Y-362381D01*
Y-362413D01*
Y-362445D01*
Y-362478D01*
Y-362510D01*
Y-362542D01*
Y-362575D01*
Y-362607D01*
Y-362639D01*
X352666Y-362691D01*
X352656Y-362743D01*
X352639Y-362792D01*
X352616Y-362840D01*
X352587Y-362883D01*
X352552Y-362923D01*
X352513Y-362957D01*
X352469Y-362986D01*
X352422Y-363010D01*
X352372Y-363026D01*
X352321Y-363036D01*
X352269Y-363040D01*
X351075D01*
X351023Y-363036D01*
X350971Y-363026D01*
X350922Y-363010D01*
X350874Y-362986D01*
X350831Y-362957D01*
X350792Y-362923D01*
X350757Y-362883D01*
X350728Y-362840D01*
X350705Y-362792D01*
X350688Y-362743D01*
X350677Y-362691D01*
X350674Y-362639D01*
Y-362607D01*
Y-362575D01*
Y-362542D01*
Y-362510D01*
Y-362478D01*
Y-362445D01*
Y-362413D01*
Y-362381D01*
Y-362349D01*
Y-362316D01*
Y-362284D01*
Y-362252D01*
Y-362220D01*
Y-362187D01*
Y-362155D01*
Y-362123D01*
Y-362091D01*
Y-362058D01*
Y-362026D01*
Y-361994D01*
Y-361962D01*
Y-361929D01*
Y-361897D01*
Y-361865D01*
Y-361832D01*
Y-361800D01*
Y-361768D01*
Y-361736D01*
Y-361703D01*
Y-361671D01*
Y-361639D01*
Y-361607D01*
Y-361575D01*
Y-361542D01*
Y-361510D01*
Y-361478D01*
Y-361445D01*
Y-361413D01*
Y-361381D01*
Y-361349D01*
Y-361316D01*
Y-361284D01*
Y-361252D01*
Y-361220D01*
Y-361187D01*
Y-361155D01*
Y-361123D01*
Y-361090D01*
Y-361058D01*
Y-361026D01*
Y-360994D01*
Y-360962D01*
Y-360929D01*
Y-360897D01*
Y-360865D01*
Y-360832D01*
Y-360800D01*
Y-360768D01*
Y-360736D01*
Y-360703D01*
Y-360671D01*
Y-360639D01*
Y-360607D01*
Y-360574D01*
Y-360542D01*
Y-360510D01*
Y-360478D01*
Y-360445D01*
Y-360413D01*
Y-360381D01*
Y-360349D01*
Y-360316D01*
Y-360284D01*
Y-360252D01*
Y-360220D01*
Y-360187D01*
Y-360155D01*
Y-360123D01*
Y-360090D01*
Y-360058D01*
Y-360026D01*
Y-359994D01*
Y-359961D01*
Y-359929D01*
Y-359897D01*
Y-359865D01*
Y-359832D01*
Y-359800D01*
Y-359768D01*
Y-359735D01*
Y-359703D01*
Y-359671D01*
Y-359639D01*
Y-359607D01*
Y-359574D01*
Y-359542D01*
Y-359510D01*
Y-359477D01*
Y-359445D01*
Y-359413D01*
Y-359381D01*
Y-359348D01*
Y-359316D01*
Y-359284D01*
Y-359252D01*
Y-359219D01*
Y-359187D01*
Y-359155D01*
Y-359123D01*
Y-359090D01*
Y-359058D01*
Y-359026D01*
Y-358994D01*
Y-358961D01*
Y-358929D01*
Y-358897D01*
Y-358864D01*
Y-358832D01*
Y-358800D01*
Y-358768D01*
Y-358735D01*
Y-358703D01*
Y-358671D01*
Y-358639D01*
Y-358606D01*
Y-358574D01*
Y-358542D01*
Y-358510D01*
Y-358477D01*
Y-358445D01*
Y-358413D01*
Y-358381D01*
Y-358348D01*
Y-358316D01*
Y-358284D01*
Y-358252D01*
Y-358219D01*
Y-358187D01*
Y-358155D01*
Y-358122D01*
Y-358090D01*
Y-358058D01*
Y-358026D01*
Y-357993D01*
Y-357961D01*
Y-357929D01*
Y-357897D01*
Y-357864D01*
Y-357832D01*
Y-357800D01*
Y-357768D01*
Y-357735D01*
Y-357703D01*
Y-357671D01*
Y-357639D01*
Y-357606D01*
Y-357574D01*
Y-357542D01*
Y-357509D01*
Y-357477D01*
Y-357445D01*
Y-357413D01*
Y-357380D01*
Y-357348D01*
Y-357316D01*
Y-357284D01*
Y-357251D01*
Y-357219D01*
Y-357187D01*
Y-357155D01*
Y-357122D01*
Y-357090D01*
Y-357058D01*
Y-357026D01*
Y-356993D01*
Y-356961D01*
Y-356929D01*
Y-356896D01*
Y-356864D01*
Y-356832D01*
Y-356800D01*
Y-356768D01*
Y-356735D01*
Y-356703D01*
Y-356671D01*
Y-356638D01*
Y-356606D01*
Y-356574D01*
Y-356542D01*
Y-356509D01*
Y-356477D01*
Y-356445D01*
Y-356413D01*
Y-356380D01*
Y-356348D01*
Y-356316D01*
Y-356283D01*
Y-356251D01*
Y-356219D01*
Y-356187D01*
Y-356154D01*
Y-356122D01*
Y-356090D01*
Y-356058D01*
Y-356025D01*
Y-355993D01*
Y-355961D01*
Y-355929D01*
Y-355896D01*
Y-355864D01*
Y-355832D01*
Y-355800D01*
Y-355767D01*
Y-355735D01*
Y-355703D01*
Y-355671D01*
Y-355638D01*
Y-355606D01*
Y-355574D01*
Y-355541D01*
Y-355509D01*
Y-355477D01*
Y-355445D01*
Y-355413D01*
Y-355380D01*
Y-355348D01*
Y-355316D01*
Y-355283D01*
Y-355251D01*
Y-355219D01*
Y-355187D01*
Y-355154D01*
Y-355122D01*
Y-355090D01*
Y-355058D01*
Y-355025D01*
Y-354993D01*
Y-354961D01*
Y-354928D01*
Y-354896D01*
Y-354864D01*
Y-354832D01*
Y-354800D01*
Y-354767D01*
Y-354735D01*
Y-354703D01*
Y-354670D01*
Y-354638D01*
Y-354606D01*
Y-354574D01*
Y-354541D01*
Y-354509D01*
Y-354477D01*
Y-354445D01*
Y-354412D01*
Y-354380D01*
Y-354348D01*
Y-354316D01*
Y-354283D01*
Y-354251D01*
Y-354219D01*
Y-354187D01*
Y-354154D01*
Y-354122D01*
Y-354090D01*
Y-354058D01*
Y-354025D01*
Y-353993D01*
Y-353961D01*
Y-353928D01*
Y-353896D01*
Y-353864D01*
Y-353832D01*
Y-353799D01*
Y-353767D01*
Y-353735D01*
Y-353703D01*
Y-353670D01*
Y-353638D01*
Y-353606D01*
Y-353573D01*
Y-353541D01*
Y-353509D01*
Y-353477D01*
Y-353445D01*
Y-353412D01*
Y-353380D01*
Y-353348D01*
Y-353315D01*
Y-353283D01*
Y-353251D01*
Y-353219D01*
Y-353186D01*
Y-353154D01*
Y-353122D01*
Y-353090D01*
Y-353057D01*
Y-353025D01*
Y-352993D01*
Y-352961D01*
Y-352928D01*
Y-352896D01*
Y-352864D01*
Y-352832D01*
Y-352799D01*
Y-352767D01*
D01*
Y-352735D01*
Y-352702D01*
Y-352670D01*
Y-352638D01*
Y-352606D01*
Y-352573D01*
Y-352541D01*
Y-352509D01*
Y-352477D01*
Y-352444D01*
Y-352412D01*
Y-352380D01*
Y-352348D01*
Y-352315D01*
Y-352283D01*
Y-352251D01*
Y-352219D01*
Y-352186D01*
Y-352154D01*
Y-352122D01*
Y-352090D01*
Y-352057D01*
Y-352025D01*
Y-351993D01*
Y-351960D01*
Y-351928D01*
Y-351896D01*
Y-351864D01*
Y-351831D01*
Y-351799D01*
Y-351767D01*
Y-351735D01*
Y-351702D01*
Y-351670D01*
Y-351638D01*
Y-351606D01*
Y-351573D01*
Y-351541D01*
Y-351509D01*
Y-351477D01*
Y-351444D01*
Y-351412D01*
Y-351380D01*
Y-351347D01*
Y-351315D01*
Y-351283D01*
Y-351251D01*
Y-351218D01*
Y-351186D01*
Y-351154D01*
Y-351122D01*
Y-351089D01*
Y-351057D01*
Y-351025D01*
Y-350993D01*
Y-350960D01*
Y-350928D01*
Y-350896D01*
Y-350864D01*
Y-350831D01*
Y-350799D01*
Y-350767D01*
Y-350734D01*
Y-350702D01*
Y-350670D01*
Y-350638D01*
Y-350606D01*
Y-350573D01*
Y-350541D01*
Y-350509D01*
Y-350476D01*
Y-350444D01*
Y-350412D01*
Y-350380D01*
Y-350347D01*
Y-350315D01*
Y-350283D01*
Y-350251D01*
Y-350218D01*
Y-350186D01*
Y-350154D01*
Y-350121D01*
Y-350089D01*
Y-350057D01*
Y-350025D01*
Y-349992D01*
Y-349960D01*
Y-349928D01*
Y-349896D01*
Y-349863D01*
Y-349831D01*
Y-349799D01*
Y-349767D01*
Y-349734D01*
Y-349702D01*
Y-349670D01*
Y-349638D01*
Y-349605D01*
Y-349573D01*
Y-349541D01*
Y-349509D01*
Y-349476D01*
Y-349444D01*
Y-349412D01*
Y-349379D01*
Y-349347D01*
Y-349315D01*
Y-349283D01*
Y-349251D01*
Y-349218D01*
Y-349186D01*
Y-349154D01*
Y-349121D01*
Y-349089D01*
Y-349057D01*
Y-349025D01*
Y-348992D01*
Y-348960D01*
Y-348928D01*
Y-348896D01*
Y-348863D01*
Y-348831D01*
Y-348799D01*
Y-348766D01*
Y-348734D01*
Y-348702D01*
Y-348670D01*
Y-348638D01*
Y-348605D01*
Y-348573D01*
Y-348541D01*
Y-348508D01*
Y-348476D01*
Y-348444D01*
Y-348412D01*
Y-348379D01*
Y-348347D01*
Y-348315D01*
Y-348283D01*
Y-348250D01*
Y-348218D01*
Y-348186D01*
Y-348154D01*
Y-348121D01*
Y-348089D01*
Y-348057D01*
Y-348025D01*
Y-347992D01*
Y-347960D01*
Y-347928D01*
Y-347896D01*
Y-347863D01*
Y-347831D01*
Y-347799D01*
Y-347766D01*
Y-347734D01*
Y-347702D01*
Y-347670D01*
Y-347637D01*
Y-347605D01*
Y-347573D01*
Y-347541D01*
Y-347508D01*
Y-347476D01*
Y-347444D01*
Y-347411D01*
Y-347379D01*
Y-347347D01*
Y-347315D01*
Y-347283D01*
Y-347250D01*
Y-347218D01*
Y-347186D01*
Y-347153D01*
Y-347121D01*
Y-347089D01*
Y-347057D01*
Y-347024D01*
Y-346992D01*
Y-346960D01*
Y-346928D01*
Y-346895D01*
Y-346863D01*
Y-346831D01*
Y-346799D01*
Y-346766D01*
Y-346734D01*
Y-346702D01*
Y-346670D01*
Y-346637D01*
Y-346605D01*
Y-346573D01*
Y-346540D01*
Y-346508D01*
Y-346476D01*
Y-346444D01*
Y-346411D01*
Y-346379D01*
Y-346347D01*
Y-346315D01*
Y-346282D01*
Y-346250D01*
Y-346218D01*
Y-346186D01*
Y-346153D01*
Y-346121D01*
Y-346089D01*
Y-346057D01*
D01*
Y-346024D01*
Y-345992D01*
Y-345960D01*
Y-345928D01*
Y-345895D01*
Y-345863D01*
Y-345831D01*
Y-345798D01*
Y-345766D01*
Y-345734D01*
Y-345702D01*
Y-345669D01*
Y-345637D01*
Y-345605D01*
Y-345573D01*
Y-345540D01*
Y-345508D01*
Y-345476D01*
Y-345444D01*
Y-345411D01*
Y-345379D01*
Y-345347D01*
Y-345315D01*
Y-345282D01*
Y-345250D01*
Y-345218D01*
Y-345185D01*
Y-345153D01*
Y-345121D01*
Y-345089D01*
Y-345056D01*
Y-345024D01*
Y-344992D01*
Y-344960D01*
Y-344927D01*
Y-344895D01*
Y-344863D01*
Y-344831D01*
Y-344798D01*
Y-344766D01*
Y-344734D01*
Y-344702D01*
Y-344669D01*
Y-344637D01*
Y-344605D01*
Y-344572D01*
Y-344540D01*
Y-344508D01*
Y-344476D01*
Y-344443D01*
Y-344411D01*
Y-344379D01*
Y-344347D01*
Y-344314D01*
Y-344282D01*
Y-344250D01*
Y-344218D01*
Y-344185D01*
Y-344153D01*
Y-344121D01*
Y-344089D01*
Y-344056D01*
Y-344024D01*
Y-343992D01*
Y-343959D01*
Y-343927D01*
Y-343895D01*
Y-343863D01*
Y-343830D01*
Y-343798D01*
Y-343766D01*
Y-343734D01*
Y-343701D01*
Y-343669D01*
Y-343637D01*
Y-343605D01*
Y-343572D01*
Y-343540D01*
Y-343508D01*
Y-343476D01*
Y-343443D01*
Y-343411D01*
Y-343379D01*
Y-343347D01*
Y-343314D01*
Y-343282D01*
Y-343250D01*
Y-343217D01*
Y-343185D01*
Y-343153D01*
Y-343121D01*
Y-343089D01*
Y-343056D01*
Y-343024D01*
Y-342992D01*
Y-342959D01*
Y-342927D01*
Y-342895D01*
Y-342863D01*
Y-342830D01*
Y-342798D01*
Y-342766D01*
Y-342734D01*
Y-342701D01*
Y-342669D01*
Y-342637D01*
Y-342604D01*
Y-342572D01*
Y-342540D01*
Y-342508D01*
Y-342476D01*
Y-342443D01*
Y-342411D01*
Y-342379D01*
Y-342346D01*
Y-342314D01*
Y-342282D01*
Y-342250D01*
Y-342217D01*
Y-342185D01*
Y-342153D01*
Y-342121D01*
Y-342088D01*
Y-342056D01*
Y-342024D01*
Y-341992D01*
Y-341959D01*
Y-341927D01*
Y-341895D01*
Y-341863D01*
Y-341830D01*
Y-341798D01*
Y-341766D01*
Y-341734D01*
Y-341701D01*
Y-341669D01*
Y-341637D01*
Y-341604D01*
Y-341572D01*
Y-341540D01*
Y-341508D01*
Y-341475D01*
Y-341443D01*
Y-341411D01*
Y-341379D01*
Y-341346D01*
Y-341314D01*
Y-341282D01*
Y-341249D01*
Y-341217D01*
Y-341185D01*
Y-341153D01*
Y-341121D01*
Y-341088D01*
Y-341056D01*
Y-341024D01*
Y-340991D01*
Y-340959D01*
Y-340927D01*
Y-340895D01*
Y-340862D01*
Y-340830D01*
Y-340798D01*
Y-340766D01*
Y-340733D01*
Y-340701D01*
Y-340669D01*
Y-340637D01*
Y-340604D01*
Y-340572D01*
Y-340540D01*
Y-340508D01*
Y-340475D01*
Y-340443D01*
Y-340411D01*
Y-340378D01*
Y-340346D01*
Y-340314D01*
Y-340282D01*
Y-340249D01*
Y-340217D01*
Y-340185D01*
Y-340153D01*
Y-340120D01*
Y-340088D01*
Y-340056D01*
Y-340024D01*
Y-339991D01*
Y-339959D01*
Y-339927D01*
Y-339895D01*
Y-339862D01*
Y-339830D01*
Y-339798D01*
Y-339766D01*
Y-339733D01*
Y-339701D01*
Y-339669D01*
Y-339636D01*
Y-339604D01*
Y-339572D01*
Y-339540D01*
Y-339507D01*
Y-339475D01*
Y-339443D01*
Y-339411D01*
Y-339378D01*
Y-339346D01*
Y-339314D01*
Y-339282D01*
Y-339249D01*
Y-339217D01*
Y-339185D01*
Y-339153D01*
Y-339120D01*
Y-339088D01*
Y-339056D01*
Y-339023D01*
Y-338991D01*
Y-338959D01*
Y-338927D01*
Y-338894D01*
Y-338862D01*
Y-338830D01*
Y-338798D01*
Y-338765D01*
Y-338733D01*
Y-338701D01*
Y-338669D01*
Y-338636D01*
Y-338604D01*
Y-338572D01*
Y-338540D01*
Y-338507D01*
Y-338475D01*
Y-338443D01*
Y-338410D01*
Y-338378D01*
Y-338346D01*
Y-338314D01*
Y-338281D01*
Y-338249D01*
Y-338217D01*
Y-338185D01*
Y-338152D01*
Y-338120D01*
Y-338088D01*
Y-338056D01*
Y-338023D01*
Y-337991D01*
Y-337959D01*
Y-337927D01*
Y-337894D01*
Y-337862D01*
Y-337830D01*
Y-337797D01*
Y-337765D01*
Y-337733D01*
Y-337701D01*
Y-337668D01*
Y-337636D01*
Y-337604D01*
Y-337572D01*
Y-337539D01*
Y-337507D01*
Y-337475D01*
Y-337443D01*
Y-337410D01*
Y-337378D01*
Y-337346D01*
Y-337314D01*
Y-337281D01*
Y-337249D01*
Y-337217D01*
Y-337185D01*
Y-337152D01*
Y-337120D01*
Y-337088D01*
Y-337055D01*
Y-337023D01*
Y-336991D01*
Y-336959D01*
Y-336927D01*
Y-336894D01*
Y-336862D01*
Y-336830D01*
Y-336797D01*
Y-336765D01*
Y-336733D01*
Y-336701D01*
Y-336668D01*
Y-336636D01*
Y-336604D01*
Y-336572D01*
Y-336539D01*
Y-336507D01*
Y-336475D01*
Y-336442D01*
Y-336410D01*
Y-336378D01*
Y-336346D01*
Y-336314D01*
Y-336281D01*
Y-336249D01*
Y-336217D01*
Y-336184D01*
Y-336152D01*
Y-336120D01*
Y-336088D01*
Y-336055D01*
Y-336023D01*
Y-335991D01*
Y-335959D01*
Y-335926D01*
Y-335894D01*
Y-335862D01*
Y-335830D01*
Y-335797D01*
Y-335765D01*
Y-335733D01*
Y-335700D01*
Y-335668D01*
Y-335636D01*
Y-335604D01*
Y-335572D01*
Y-335539D01*
Y-335507D01*
Y-335475D01*
Y-335442D01*
Y-335410D01*
Y-335378D01*
Y-335346D01*
Y-335313D01*
Y-335281D01*
Y-335249D01*
Y-335217D01*
Y-335184D01*
Y-335152D01*
D01*
Y-335120D01*
Y-335087D01*
Y-335055D01*
Y-335023D01*
Y-334991D01*
Y-334959D01*
Y-334926D01*
Y-334894D01*
Y-334862D01*
Y-334829D01*
Y-334797D01*
Y-334765D01*
Y-334733D01*
Y-334700D01*
Y-334668D01*
Y-334636D01*
Y-334604D01*
Y-334571D01*
Y-334539D01*
Y-334507D01*
Y-334474D01*
Y-334442D01*
Y-334410D01*
Y-334378D01*
Y-334346D01*
Y-334313D01*
Y-334281D01*
Y-334249D01*
Y-334216D01*
Y-334184D01*
Y-334152D01*
Y-334120D01*
Y-334087D01*
Y-334055D01*
Y-334023D01*
Y-333991D01*
Y-333958D01*
Y-333926D01*
Y-333894D01*
Y-333862D01*
Y-333829D01*
Y-333797D01*
Y-333765D01*
Y-333733D01*
Y-333700D01*
Y-333668D01*
Y-333636D01*
Y-333604D01*
Y-333571D01*
Y-333539D01*
Y-333507D01*
Y-333474D01*
Y-333442D01*
Y-333410D01*
Y-333378D01*
Y-333345D01*
Y-333313D01*
Y-333281D01*
Y-333249D01*
Y-333216D01*
Y-333184D01*
Y-333152D01*
Y-333120D01*
Y-333087D01*
Y-333055D01*
Y-333023D01*
Y-332991D01*
Y-332958D01*
Y-332926D01*
Y-332894D01*
Y-332861D01*
Y-332829D01*
Y-332797D01*
Y-332765D01*
Y-332732D01*
Y-332700D01*
Y-332668D01*
Y-332636D01*
Y-332603D01*
Y-332571D01*
Y-332539D01*
Y-332507D01*
Y-332474D01*
Y-332442D01*
Y-332410D01*
Y-332378D01*
Y-332345D01*
Y-332313D01*
Y-332281D01*
Y-332248D01*
Y-332216D01*
Y-332184D01*
Y-332152D01*
Y-332119D01*
Y-332087D01*
Y-332055D01*
Y-332023D01*
Y-331990D01*
Y-331958D01*
Y-331926D01*
Y-331894D01*
Y-331861D01*
Y-331829D01*
Y-331797D01*
Y-331765D01*
Y-331732D01*
Y-331700D01*
Y-331668D01*
Y-331635D01*
Y-331603D01*
Y-331571D01*
Y-331539D01*
Y-331506D01*
Y-331474D01*
Y-331442D01*
Y-331410D01*
Y-331377D01*
Y-331345D01*
Y-331313D01*
Y-331281D01*
Y-331248D01*
Y-331216D01*
Y-331184D01*
Y-331152D01*
Y-331119D01*
Y-331087D01*
Y-331055D01*
Y-331023D01*
Y-330990D01*
Y-330958D01*
Y-330926D01*
Y-330893D01*
Y-330861D01*
Y-330829D01*
Y-330797D01*
Y-330764D01*
Y-330732D01*
Y-330700D01*
Y-330668D01*
Y-330635D01*
Y-330603D01*
Y-330571D01*
Y-330539D01*
Y-330506D01*
Y-330474D01*
Y-330442D01*
Y-330410D01*
Y-330377D01*
Y-330345D01*
Y-330313D01*
Y-330280D01*
Y-330248D01*
Y-330216D01*
Y-330184D01*
Y-330152D01*
Y-330119D01*
Y-330087D01*
Y-330055D01*
Y-330022D01*
Y-329990D01*
Y-329958D01*
Y-329926D01*
Y-329893D01*
Y-329861D01*
Y-329829D01*
Y-329797D01*
Y-329764D01*
Y-329732D01*
Y-329700D01*
Y-329667D01*
Y-329635D01*
Y-329603D01*
Y-329571D01*
Y-329538D01*
Y-329506D01*
Y-329474D01*
Y-329442D01*
Y-329410D01*
Y-329377D01*
Y-329345D01*
Y-329313D01*
Y-329280D01*
Y-329248D01*
Y-329216D01*
Y-329184D01*
Y-329151D01*
Y-329119D01*
Y-329087D01*
Y-329055D01*
Y-329022D01*
Y-328990D01*
Y-328958D01*
Y-328925D01*
Y-328893D01*
Y-328861D01*
Y-328829D01*
Y-328797D01*
Y-328764D01*
Y-328732D01*
Y-328700D01*
Y-328667D01*
Y-328635D01*
Y-328603D01*
Y-328571D01*
Y-328538D01*
Y-328506D01*
Y-328474D01*
Y-328442D01*
Y-328409D01*
Y-328377D01*
Y-328345D01*
Y-328313D01*
Y-328280D01*
Y-328248D01*
Y-328216D01*
Y-328184D01*
Y-328151D01*
Y-328119D01*
Y-328087D01*
Y-328054D01*
Y-328022D01*
Y-327990D01*
Y-327958D01*
Y-327925D01*
Y-327893D01*
Y-327889D01*
X350672Y-327885D01*
X350656Y-327836D01*
X350645Y-327784D01*
X350642Y-327732D01*
Y-327728D01*
X350640Y-327724D01*
X350637Y-327716D01*
X350631Y-327706D01*
X350608Y-327659D01*
X350605Y-327651D01*
X350599Y-327642D01*
X350584Y-327613D01*
X350563Y-327589D01*
X350534Y-327545D01*
X350529Y-327535D01*
X350520Y-327531D01*
X350476Y-327501D01*
X350452Y-327481D01*
X350423Y-327466D01*
X350413Y-327460D01*
X350405Y-327457D01*
X350358Y-327434D01*
X350349Y-327427D01*
X350341Y-327425D01*
X350333Y-327421D01*
X350313Y-327419D01*
X350261Y-327409D01*
X350212Y-327392D01*
X350208Y-327391D01*
X346268D01*
X346216Y-327387D01*
X346164Y-327377D01*
X346114Y-327360D01*
X346068Y-327337D01*
X346024Y-327308D01*
X345985Y-327273D01*
X345950Y-327234D01*
X345921Y-327190D01*
X345898Y-327143D01*
X345881Y-327094D01*
X345870Y-327042D01*
X345867Y-326990D01*
Y-326958D01*
Y-326925D01*
Y-326893D01*
Y-326861D01*
Y-326829D01*
Y-326796D01*
Y-326764D01*
Y-326732D01*
Y-326699D01*
Y-326667D01*
Y-326635D01*
Y-326603D01*
Y-326570D01*
Y-326538D01*
Y-326506D01*
Y-326474D01*
Y-326441D01*
Y-326409D01*
Y-326377D01*
Y-326345D01*
Y-326312D01*
Y-326280D01*
Y-326248D01*
Y-326216D01*
Y-326183D01*
Y-326151D01*
Y-326119D01*
Y-326086D01*
Y-326054D01*
Y-326022D01*
Y-325990D01*
Y-325957D01*
Y-325925D01*
Y-325893D01*
Y-325861D01*
Y-325828D01*
Y-325796D01*
Y-325764D01*
X345870Y-325712D01*
X345881Y-325660D01*
X345898Y-325610D01*
X345921Y-325564D01*
X345950Y-325520D01*
X345985Y-325480D01*
X346024Y-325446D01*
X346068Y-325417D01*
X346114Y-325394D01*
X346164Y-325377D01*
X346216Y-325366D01*
X346268Y-325363D01*
X350365D01*
X350417Y-325366D01*
D02*
G37*
%LPC*%
G36*
X356191Y-339070D02*
X355652D01*
X355666Y-339081D01*
X355695Y-339096D01*
X355739Y-339125D01*
X355763Y-339146D01*
X355792Y-339160D01*
X355836Y-339189D01*
X355875Y-339224D01*
X355890Y-339241D01*
X355907Y-339256D01*
X355922Y-339273D01*
X355940Y-339288D01*
X355955Y-339306D01*
X355972Y-339321D01*
X355987Y-339338D01*
X356004Y-339353D01*
X356019Y-339370D01*
X356036Y-339385D01*
X356071Y-339425D01*
X356100Y-339468D01*
X356115Y-339498D01*
X356135Y-339522D01*
X356165Y-339565D01*
X356179Y-339594D01*
X356191Y-339608D01*
Y-339604D01*
Y-339572D01*
Y-339540D01*
Y-339507D01*
Y-339475D01*
Y-339443D01*
Y-339411D01*
Y-339378D01*
Y-339346D01*
D01*
Y-339314D01*
Y-339282D01*
Y-339249D01*
Y-339217D01*
Y-339185D01*
Y-339153D01*
Y-339120D01*
Y-339088D01*
Y-339070D01*
D02*
G37*
G36*
X379760Y-334037D02*
X376299D01*
X376296Y-334038D01*
X376246Y-334055D01*
X376195Y-334065D01*
X376142Y-334069D01*
X376138D01*
X376134Y-334071D01*
X376085Y-334087D01*
X376058Y-334093D01*
X376055Y-334094D01*
X376054Y-334096D01*
X376042Y-334109D01*
X376039Y-334113D01*
X376021Y-334128D01*
X376006Y-334145D01*
X375989Y-334160D01*
X375974Y-334177D01*
X375957Y-334192D01*
X375950Y-334200D01*
X375942Y-334210D01*
X375925Y-334225D01*
X375910Y-334242D01*
X375892Y-334257D01*
X375877Y-334274D01*
X375860Y-334289D01*
X375848Y-334303D01*
X375845Y-334306D01*
X375828Y-334321D01*
X375813Y-334339D01*
X375796Y-334354D01*
X375781Y-334371D01*
X375763Y-334386D01*
X375748Y-334403D01*
X375731Y-334418D01*
X375722Y-334429D01*
X375716Y-334435D01*
X375699Y-334451D01*
X375684Y-334468D01*
X375667Y-334483D01*
X375652Y-334500D01*
X375634Y-334515D01*
X375619Y-334532D01*
X375602Y-334547D01*
X375587Y-334564D01*
X375571Y-334578D01*
X375570Y-334579D01*
X375555Y-334597D01*
X375537Y-334612D01*
X375522Y-334629D01*
X375505Y-334644D01*
X375490Y-334661D01*
X375473Y-334676D01*
X375458Y-334694D01*
X375441Y-334709D01*
X375426Y-334726D01*
X375408Y-334741D01*
X375393Y-334758D01*
X375376Y-334773D01*
X375361Y-334790D01*
X375344Y-334805D01*
X375339Y-334811D01*
X375329Y-334823D01*
X375312Y-334838D01*
X375297Y-334855D01*
X375279Y-334870D01*
X375271Y-334880D01*
X375266Y-334886D01*
X375255Y-334918D01*
X375253Y-334922D01*
Y-334926D01*
X375249Y-334979D01*
X375239Y-335030D01*
X375222Y-335080D01*
X375220Y-335083D01*
Y-335087D01*
Y-335120D01*
Y-335152D01*
Y-335184D01*
Y-335217D01*
Y-335249D01*
Y-335281D01*
Y-335313D01*
Y-335346D01*
Y-335378D01*
Y-335410D01*
Y-335442D01*
Y-335475D01*
Y-335507D01*
Y-335539D01*
Y-335572D01*
Y-335604D01*
Y-335636D01*
Y-335668D01*
Y-335700D01*
Y-335733D01*
Y-335765D01*
Y-335797D01*
Y-335830D01*
Y-335862D01*
Y-335894D01*
Y-335926D01*
Y-335959D01*
Y-335991D01*
Y-336023D01*
Y-336055D01*
Y-336088D01*
Y-336120D01*
Y-336152D01*
Y-336184D01*
Y-336217D01*
Y-336249D01*
Y-336281D01*
Y-336314D01*
Y-336346D01*
Y-336378D01*
Y-336410D01*
Y-336442D01*
Y-336475D01*
Y-336507D01*
Y-336539D01*
Y-336572D01*
Y-336604D01*
Y-336636D01*
Y-336668D01*
Y-336701D01*
Y-336733D01*
Y-336765D01*
Y-336797D01*
Y-336830D01*
Y-336862D01*
Y-336894D01*
Y-336927D01*
Y-336959D01*
Y-336991D01*
Y-337023D01*
Y-337055D01*
Y-337088D01*
Y-337120D01*
Y-337152D01*
Y-337185D01*
Y-337217D01*
Y-337249D01*
Y-337281D01*
Y-337314D01*
Y-337346D01*
Y-337378D01*
Y-337410D01*
Y-337443D01*
Y-337475D01*
Y-337507D01*
Y-337539D01*
Y-337572D01*
Y-337604D01*
Y-337636D01*
Y-337668D01*
Y-337701D01*
Y-337733D01*
Y-337765D01*
Y-337797D01*
Y-337830D01*
Y-337862D01*
Y-337894D01*
Y-337927D01*
Y-337959D01*
Y-337991D01*
Y-338023D01*
Y-338056D01*
D01*
Y-338088D01*
Y-338120D01*
Y-338152D01*
Y-338185D01*
Y-338217D01*
Y-338249D01*
Y-338281D01*
Y-338314D01*
Y-338346D01*
Y-338378D01*
Y-338410D01*
Y-338443D01*
Y-338475D01*
Y-338507D01*
Y-338540D01*
Y-338572D01*
Y-338604D01*
Y-338636D01*
Y-338669D01*
Y-338701D01*
Y-338733D01*
Y-338765D01*
Y-338798D01*
Y-338830D01*
Y-338862D01*
Y-338894D01*
Y-338927D01*
Y-338959D01*
Y-338991D01*
Y-339023D01*
Y-339056D01*
Y-339088D01*
Y-339120D01*
Y-339153D01*
Y-339185D01*
Y-339217D01*
Y-339249D01*
Y-339254D01*
X375222Y-339257D01*
X375239Y-339307D01*
X375249Y-339358D01*
X375253Y-339411D01*
Y-339415D01*
X375255Y-339419D01*
X375257Y-339426D01*
X375264Y-339436D01*
X375278Y-339465D01*
X375279Y-339467D01*
X375297Y-339482D01*
X375312Y-339499D01*
X375329Y-339514D01*
X375344Y-339531D01*
X375361Y-339547D01*
X375376Y-339564D01*
X375393Y-339579D01*
X375407Y-339594D01*
X375409Y-339596D01*
X375426Y-339611D01*
X375441Y-339628D01*
X375458Y-339643D01*
X375473Y-339661D01*
X375490Y-339676D01*
X375505Y-339693D01*
X375522Y-339708D01*
X375537Y-339725D01*
X375555Y-339740D01*
X375566Y-339753D01*
X375570Y-339757D01*
X375587Y-339772D01*
X375602Y-339790D01*
X375619Y-339805D01*
X375634Y-339822D01*
X375652Y-339837D01*
X375667Y-339854D01*
X375684Y-339869D01*
X375699Y-339886D01*
X375716Y-339901D01*
X375731Y-339919D01*
X375748Y-339934D01*
X375763Y-339951D01*
X375781Y-339966D01*
X375796Y-339983D01*
X375813Y-339998D01*
X375828Y-340015D01*
X375845Y-340031D01*
X375860Y-340048D01*
X375877Y-340063D01*
X375892Y-340080D01*
X375910Y-340095D01*
X375925Y-340112D01*
X375942Y-340127D01*
X375957Y-340144D01*
X375974Y-340160D01*
X375989Y-340177D01*
X376006Y-340192D01*
X376021Y-340209D01*
X376039Y-340224D01*
X376049Y-340236D01*
X376051Y-340238D01*
X376066Y-340239D01*
X376117Y-340249D01*
X376167Y-340266D01*
X376170Y-340268D01*
X379806D01*
Y-340249D01*
Y-340217D01*
Y-340185D01*
Y-340153D01*
Y-340120D01*
Y-340088D01*
Y-340056D01*
Y-340024D01*
Y-339991D01*
Y-339959D01*
Y-339927D01*
Y-339895D01*
Y-339862D01*
Y-339830D01*
Y-339798D01*
Y-339766D01*
Y-339733D01*
Y-339701D01*
Y-339669D01*
Y-339636D01*
Y-339604D01*
Y-339572D01*
Y-339540D01*
Y-339507D01*
Y-339475D01*
Y-339443D01*
Y-339424D01*
X376626D01*
X376574Y-339421D01*
X376522Y-339411D01*
X376473Y-339394D01*
X376426Y-339371D01*
X376382Y-339341D01*
X376343Y-339307D01*
X376328Y-339290D01*
X376311Y-339275D01*
X376276Y-339235D01*
X376247Y-339192D01*
X376224Y-339145D01*
X376207Y-339095D01*
X376197Y-339043D01*
X376193Y-338991D01*
Y-338959D01*
Y-338927D01*
Y-338894D01*
Y-338862D01*
Y-338830D01*
Y-338798D01*
Y-338765D01*
Y-338733D01*
Y-338701D01*
Y-338669D01*
Y-338636D01*
Y-338604D01*
Y-338572D01*
Y-338540D01*
Y-338507D01*
Y-338475D01*
Y-338443D01*
Y-338410D01*
Y-338378D01*
Y-338346D01*
Y-338314D01*
Y-338281D01*
Y-338249D01*
Y-338217D01*
Y-338185D01*
Y-338152D01*
Y-338120D01*
Y-338088D01*
Y-338056D01*
Y-338023D01*
Y-337991D01*
Y-337959D01*
Y-337927D01*
Y-337894D01*
X376197Y-337842D01*
X376207Y-337791D01*
X376224Y-337741D01*
X376247Y-337694D01*
X376276Y-337650D01*
X376311Y-337611D01*
X376311Y-337611D01*
X376328Y-337596D01*
X376343Y-337579D01*
X376382Y-337544D01*
X376426Y-337515D01*
X376473Y-337492D01*
X376522Y-337475D01*
X376574Y-337465D01*
X376626Y-337461D01*
X379290D01*
Y-337443D01*
Y-337410D01*
Y-337378D01*
Y-337346D01*
Y-337314D01*
Y-337281D01*
Y-337249D01*
Y-337217D01*
Y-337185D01*
Y-337152D01*
Y-337120D01*
Y-337088D01*
Y-337055D01*
Y-337023D01*
Y-336991D01*
Y-336959D01*
Y-336927D01*
Y-336894D01*
Y-336876D01*
X376626D01*
X376574Y-336872D01*
X376522Y-336862D01*
X376473Y-336845D01*
X376426Y-336822D01*
X376382Y-336793D01*
X376343Y-336758D01*
X376328Y-336741D01*
X376311Y-336726D01*
X376276Y-336687D01*
X376247Y-336643D01*
X376224Y-336596D01*
X376207Y-336546D01*
X376197Y-336495D01*
X376193Y-336442D01*
Y-336410D01*
Y-336378D01*
Y-336346D01*
Y-336314D01*
Y-336281D01*
Y-336249D01*
Y-336217D01*
Y-336184D01*
Y-336152D01*
Y-336120D01*
Y-336088D01*
D01*
Y-336055D01*
Y-336023D01*
Y-335991D01*
Y-335959D01*
Y-335926D01*
Y-335894D01*
Y-335862D01*
Y-335830D01*
Y-335797D01*
Y-335765D01*
Y-335733D01*
Y-335700D01*
Y-335668D01*
Y-335636D01*
Y-335604D01*
Y-335572D01*
Y-335539D01*
Y-335507D01*
Y-335475D01*
Y-335442D01*
Y-335410D01*
Y-335378D01*
Y-335346D01*
Y-335313D01*
X376197Y-335261D01*
X376207Y-335210D01*
X376224Y-335160D01*
X376247Y-335113D01*
X376276Y-335069D01*
X376311Y-335030D01*
X376328Y-335015D01*
X376343Y-334998D01*
X376382Y-334963D01*
X376426Y-334934D01*
X376473Y-334911D01*
X376522Y-334894D01*
X376574Y-334884D01*
X376626Y-334880D01*
X379806D01*
Y-334862D01*
Y-334829D01*
Y-334797D01*
Y-334765D01*
Y-334733D01*
Y-334700D01*
Y-334668D01*
Y-334636D01*
Y-334604D01*
Y-334571D01*
Y-334539D01*
Y-334507D01*
Y-334474D01*
Y-334442D01*
Y-334410D01*
Y-334378D01*
Y-334346D01*
Y-334313D01*
Y-334281D01*
Y-334249D01*
Y-334216D01*
Y-334184D01*
Y-334152D01*
Y-334120D01*
Y-334087D01*
Y-334055D01*
Y-334053D01*
X379764Y-334038D01*
X379760Y-334037D01*
D02*
G37*
G36*
X371354D02*
X367058D01*
Y-334055D01*
Y-334087D01*
Y-334120D01*
Y-334152D01*
Y-334184D01*
Y-334216D01*
Y-334249D01*
Y-334281D01*
Y-334313D01*
Y-334346D01*
Y-334378D01*
Y-334410D01*
Y-334442D01*
Y-334474D01*
Y-334507D01*
Y-334539D01*
Y-334571D01*
Y-334604D01*
Y-334636D01*
Y-334668D01*
Y-334700D01*
Y-334733D01*
Y-334765D01*
Y-334797D01*
Y-334829D01*
Y-334862D01*
Y-334894D01*
Y-334926D01*
Y-334959D01*
Y-334991D01*
Y-335023D01*
Y-335055D01*
Y-335087D01*
Y-335120D01*
Y-335152D01*
Y-335184D01*
Y-335217D01*
Y-335249D01*
Y-335281D01*
Y-335313D01*
Y-335346D01*
Y-335378D01*
Y-335410D01*
Y-335442D01*
Y-335475D01*
Y-335507D01*
Y-335539D01*
Y-335572D01*
Y-335604D01*
Y-335636D01*
Y-335668D01*
Y-335700D01*
Y-335733D01*
Y-335765D01*
Y-335797D01*
Y-335830D01*
Y-335862D01*
Y-335894D01*
Y-335926D01*
Y-335959D01*
Y-335991D01*
Y-336023D01*
Y-336055D01*
Y-336088D01*
Y-336120D01*
Y-336152D01*
Y-336184D01*
Y-336217D01*
Y-336249D01*
Y-336281D01*
Y-336314D01*
Y-336346D01*
Y-336378D01*
Y-336410D01*
Y-336442D01*
Y-336475D01*
Y-336507D01*
Y-336539D01*
Y-336572D01*
Y-336604D01*
Y-336636D01*
Y-336668D01*
Y-336701D01*
Y-336733D01*
Y-336765D01*
Y-336797D01*
Y-336830D01*
Y-336862D01*
Y-336894D01*
Y-336927D01*
Y-336959D01*
Y-336991D01*
Y-337023D01*
Y-337055D01*
Y-337088D01*
Y-337120D01*
Y-337152D01*
Y-337185D01*
Y-337217D01*
Y-337249D01*
Y-337281D01*
Y-337314D01*
Y-337346D01*
Y-337378D01*
Y-337410D01*
Y-337443D01*
Y-337475D01*
Y-337507D01*
Y-337539D01*
Y-337572D01*
Y-337604D01*
Y-337636D01*
Y-337668D01*
Y-337701D01*
Y-337733D01*
Y-337765D01*
Y-337797D01*
Y-337830D01*
Y-337862D01*
Y-337894D01*
Y-337927D01*
Y-337959D01*
Y-337991D01*
Y-338023D01*
Y-338056D01*
Y-338088D01*
Y-338120D01*
Y-338152D01*
Y-338185D01*
Y-338217D01*
Y-338249D01*
Y-338281D01*
Y-338314D01*
Y-338346D01*
Y-338378D01*
Y-338410D01*
Y-338443D01*
Y-338475D01*
Y-338507D01*
Y-338540D01*
Y-338572D01*
Y-338604D01*
Y-338636D01*
Y-338669D01*
Y-338701D01*
Y-338733D01*
Y-338765D01*
Y-338798D01*
Y-338830D01*
Y-338862D01*
Y-338894D01*
Y-338927D01*
Y-338959D01*
Y-338991D01*
Y-339023D01*
Y-339056D01*
Y-339088D01*
Y-339120D01*
Y-339153D01*
Y-339185D01*
Y-339217D01*
Y-339249D01*
Y-339282D01*
Y-339314D01*
Y-339346D01*
Y-339378D01*
Y-339411D01*
Y-339443D01*
Y-339475D01*
Y-339507D01*
Y-339540D01*
Y-339572D01*
Y-339604D01*
Y-339636D01*
Y-339669D01*
Y-339701D01*
Y-339733D01*
Y-339766D01*
Y-339798D01*
Y-339830D01*
Y-339862D01*
Y-339895D01*
Y-339927D01*
Y-339959D01*
Y-339991D01*
Y-340024D01*
Y-340056D01*
Y-340088D01*
Y-340120D01*
Y-340153D01*
Y-340185D01*
Y-340217D01*
Y-340249D01*
Y-340268D01*
X368031D01*
Y-340249D01*
Y-340217D01*
Y-340185D01*
Y-340153D01*
Y-340120D01*
Y-340088D01*
Y-340056D01*
Y-340024D01*
Y-339991D01*
Y-339959D01*
Y-339927D01*
Y-339895D01*
Y-339862D01*
Y-339830D01*
Y-339798D01*
Y-339766D01*
Y-339733D01*
Y-339701D01*
Y-339669D01*
Y-339636D01*
Y-339604D01*
Y-339572D01*
Y-339540D01*
Y-339507D01*
Y-339475D01*
Y-339443D01*
Y-339411D01*
Y-339378D01*
Y-339346D01*
Y-339314D01*
Y-339282D01*
Y-339249D01*
Y-339217D01*
Y-339185D01*
Y-339153D01*
Y-339120D01*
Y-339088D01*
Y-339056D01*
Y-339023D01*
Y-338991D01*
Y-338959D01*
Y-338927D01*
Y-338894D01*
Y-338862D01*
Y-338830D01*
Y-338798D01*
Y-338765D01*
Y-338733D01*
Y-338701D01*
Y-338669D01*
Y-338636D01*
Y-338604D01*
Y-338572D01*
Y-338540D01*
Y-338507D01*
Y-338475D01*
Y-338443D01*
Y-338410D01*
Y-338378D01*
Y-338346D01*
Y-338314D01*
Y-338281D01*
Y-338249D01*
Y-338217D01*
Y-338185D01*
Y-338152D01*
Y-338120D01*
Y-338088D01*
Y-338056D01*
Y-338023D01*
Y-337991D01*
Y-337959D01*
Y-337927D01*
Y-337894D01*
Y-337862D01*
Y-337830D01*
Y-337797D01*
Y-337765D01*
Y-337733D01*
Y-337701D01*
Y-337668D01*
Y-337636D01*
Y-337604D01*
Y-337572D01*
Y-337539D01*
Y-337507D01*
Y-337475D01*
Y-337443D01*
Y-337410D01*
Y-337378D01*
Y-337346D01*
Y-337314D01*
Y-337281D01*
Y-337249D01*
Y-337217D01*
Y-337185D01*
Y-337152D01*
Y-337120D01*
Y-337088D01*
Y-337055D01*
Y-337023D01*
Y-336991D01*
Y-336959D01*
Y-336927D01*
Y-336894D01*
Y-336862D01*
Y-336830D01*
Y-336797D01*
Y-336765D01*
Y-336733D01*
Y-336701D01*
Y-336668D01*
Y-336636D01*
Y-336604D01*
Y-336572D01*
Y-336539D01*
Y-336507D01*
Y-336475D01*
Y-336442D01*
Y-336410D01*
Y-336378D01*
Y-336346D01*
Y-336314D01*
Y-336281D01*
Y-336249D01*
Y-336217D01*
Y-336184D01*
Y-336152D01*
Y-336120D01*
Y-336088D01*
D01*
Y-336055D01*
Y-336023D01*
Y-335991D01*
Y-335959D01*
Y-335926D01*
Y-335894D01*
Y-335862D01*
Y-335830D01*
Y-335797D01*
Y-335765D01*
Y-335733D01*
Y-335700D01*
Y-335668D01*
Y-335636D01*
Y-335604D01*
Y-335572D01*
Y-335539D01*
Y-335507D01*
Y-335475D01*
Y-335442D01*
Y-335410D01*
Y-335378D01*
X368034Y-335326D01*
X368045Y-335274D01*
X368061Y-335225D01*
X368085Y-335177D01*
X368114Y-335134D01*
X368148Y-335094D01*
X368188Y-335060D01*
X368231Y-335031D01*
X368278Y-335008D01*
X368328Y-334991D01*
X368379Y-334981D01*
X368432Y-334977D01*
X369529D01*
X369581Y-334981D01*
X369632Y-334991D01*
X369682Y-335008D01*
X369729Y-335031D01*
X369773Y-335060D01*
X369812Y-335094D01*
X369847Y-335134D01*
X369876Y-335177D01*
X369899Y-335225D01*
X369916Y-335274D01*
X369926Y-335326D01*
X369930Y-335378D01*
Y-335410D01*
Y-335442D01*
Y-335475D01*
Y-335507D01*
Y-335539D01*
Y-335572D01*
Y-335604D01*
Y-335636D01*
Y-335668D01*
Y-335700D01*
Y-335733D01*
Y-335765D01*
Y-335797D01*
Y-335830D01*
Y-335862D01*
Y-335894D01*
Y-335926D01*
Y-335959D01*
Y-335991D01*
Y-336023D01*
Y-336055D01*
Y-336088D01*
Y-336120D01*
Y-336152D01*
Y-336184D01*
Y-336217D01*
Y-336249D01*
Y-336281D01*
Y-336314D01*
Y-336346D01*
Y-336378D01*
Y-336410D01*
Y-336442D01*
Y-336475D01*
Y-336507D01*
Y-336539D01*
Y-336572D01*
Y-336604D01*
Y-336636D01*
Y-336668D01*
Y-336701D01*
Y-336733D01*
Y-336765D01*
Y-336797D01*
Y-336830D01*
Y-336862D01*
Y-336894D01*
Y-336927D01*
Y-336959D01*
Y-336991D01*
Y-337023D01*
Y-337055D01*
Y-337088D01*
Y-337120D01*
Y-337152D01*
Y-337185D01*
Y-337217D01*
Y-337249D01*
Y-337281D01*
Y-337314D01*
Y-337346D01*
Y-337378D01*
Y-337410D01*
Y-337443D01*
Y-337475D01*
Y-337507D01*
Y-337539D01*
Y-337572D01*
Y-337604D01*
Y-337636D01*
Y-337668D01*
Y-337701D01*
Y-337733D01*
Y-337765D01*
Y-337797D01*
Y-337830D01*
Y-337862D01*
Y-337894D01*
Y-337927D01*
Y-337959D01*
Y-337991D01*
Y-338023D01*
Y-338056D01*
D01*
Y-338088D01*
Y-338120D01*
Y-338152D01*
Y-338185D01*
Y-338217D01*
Y-338249D01*
Y-338281D01*
Y-338314D01*
Y-338346D01*
Y-338378D01*
Y-338410D01*
Y-338443D01*
Y-338475D01*
Y-338507D01*
Y-338540D01*
Y-338572D01*
Y-338604D01*
Y-338636D01*
Y-338669D01*
Y-338701D01*
Y-338733D01*
Y-338765D01*
Y-338798D01*
Y-338830D01*
Y-338862D01*
Y-338894D01*
Y-338927D01*
Y-338959D01*
Y-338991D01*
Y-339023D01*
Y-339056D01*
Y-339088D01*
Y-339120D01*
Y-339153D01*
Y-339185D01*
Y-339217D01*
Y-339249D01*
Y-339282D01*
Y-339314D01*
Y-339346D01*
Y-339378D01*
Y-339411D01*
Y-339443D01*
Y-339475D01*
Y-339507D01*
Y-339540D01*
Y-339572D01*
Y-339604D01*
Y-339636D01*
Y-339669D01*
Y-339701D01*
Y-339733D01*
Y-339766D01*
Y-339798D01*
Y-339830D01*
Y-339862D01*
Y-339895D01*
Y-339927D01*
Y-339959D01*
Y-339991D01*
Y-340024D01*
Y-340056D01*
Y-340088D01*
Y-340120D01*
Y-340153D01*
Y-340185D01*
Y-340217D01*
Y-340249D01*
Y-340268D01*
X370773D01*
Y-340249D01*
Y-340217D01*
Y-340185D01*
Y-340153D01*
Y-340120D01*
Y-340088D01*
Y-340056D01*
Y-340024D01*
Y-339991D01*
Y-339959D01*
Y-339927D01*
Y-339895D01*
Y-339862D01*
Y-339830D01*
Y-339798D01*
Y-339766D01*
Y-339733D01*
Y-339701D01*
Y-339669D01*
Y-339636D01*
Y-339604D01*
Y-339572D01*
Y-339540D01*
Y-339507D01*
Y-339475D01*
Y-339443D01*
Y-339411D01*
Y-339378D01*
Y-339346D01*
Y-339314D01*
Y-339282D01*
Y-339249D01*
Y-339217D01*
Y-339185D01*
Y-339153D01*
Y-339120D01*
Y-339088D01*
Y-339056D01*
Y-339023D01*
Y-338991D01*
Y-338959D01*
Y-338927D01*
Y-338894D01*
Y-338862D01*
Y-338830D01*
Y-338798D01*
Y-338765D01*
Y-338733D01*
Y-338701D01*
Y-338669D01*
Y-338636D01*
Y-338604D01*
Y-338572D01*
Y-338540D01*
Y-338507D01*
Y-338475D01*
Y-338443D01*
Y-338410D01*
Y-338378D01*
Y-338346D01*
Y-338314D01*
Y-338281D01*
Y-338249D01*
Y-338217D01*
Y-338185D01*
Y-338152D01*
Y-338120D01*
Y-338088D01*
Y-338056D01*
Y-338023D01*
Y-337991D01*
Y-337959D01*
Y-337927D01*
Y-337894D01*
Y-337862D01*
Y-337830D01*
Y-337797D01*
Y-337765D01*
Y-337733D01*
Y-337701D01*
Y-337668D01*
Y-337636D01*
Y-337604D01*
Y-337572D01*
Y-337539D01*
Y-337507D01*
Y-337475D01*
Y-337443D01*
Y-337410D01*
Y-337378D01*
Y-337346D01*
Y-337314D01*
Y-337281D01*
Y-337249D01*
Y-337217D01*
Y-337185D01*
Y-337152D01*
Y-337120D01*
Y-337088D01*
Y-337055D01*
Y-337023D01*
Y-336991D01*
Y-336959D01*
Y-336927D01*
Y-336894D01*
Y-336862D01*
Y-336830D01*
Y-336797D01*
Y-336765D01*
Y-336733D01*
Y-336701D01*
Y-336668D01*
Y-336636D01*
Y-336604D01*
Y-336572D01*
Y-336539D01*
Y-336507D01*
Y-336475D01*
Y-336442D01*
Y-336410D01*
Y-336378D01*
Y-336346D01*
Y-336314D01*
Y-336281D01*
Y-336249D01*
Y-336217D01*
Y-336184D01*
Y-336152D01*
Y-336120D01*
Y-336088D01*
D01*
Y-336055D01*
Y-336023D01*
Y-335991D01*
Y-335959D01*
Y-335926D01*
Y-335894D01*
Y-335862D01*
Y-335830D01*
Y-335797D01*
Y-335765D01*
Y-335733D01*
Y-335700D01*
Y-335668D01*
Y-335636D01*
Y-335604D01*
Y-335572D01*
Y-335539D01*
Y-335507D01*
Y-335475D01*
Y-335442D01*
Y-335410D01*
Y-335378D01*
X370777Y-335326D01*
X370787Y-335274D01*
X370804Y-335225D01*
X370827Y-335177D01*
X370856Y-335134D01*
X370891Y-335094D01*
X370930Y-335060D01*
X370974Y-335031D01*
X371021Y-335008D01*
X371070Y-334991D01*
X371122Y-334981D01*
X371174Y-334977D01*
X371354D01*
Y-334959D01*
Y-334926D01*
Y-334894D01*
Y-334862D01*
Y-334829D01*
Y-334797D01*
Y-334765D01*
Y-334733D01*
Y-334700D01*
Y-334668D01*
Y-334636D01*
Y-334604D01*
Y-334571D01*
Y-334539D01*
Y-334507D01*
Y-334474D01*
Y-334442D01*
Y-334410D01*
Y-334378D01*
Y-334346D01*
Y-334313D01*
Y-334281D01*
Y-334249D01*
Y-334216D01*
Y-334184D01*
Y-334152D01*
Y-334120D01*
Y-334087D01*
Y-334055D01*
Y-334037D01*
D02*
G37*
G36*
X365450D02*
X364477D01*
Y-334055D01*
Y-334087D01*
Y-334120D01*
Y-334152D01*
Y-334184D01*
Y-334216D01*
Y-334249D01*
Y-334281D01*
Y-334313D01*
Y-334346D01*
Y-334378D01*
Y-334410D01*
Y-334442D01*
Y-334474D01*
Y-334507D01*
Y-334539D01*
Y-334571D01*
Y-334604D01*
Y-334636D01*
Y-334668D01*
Y-334700D01*
Y-334733D01*
Y-334765D01*
Y-334797D01*
Y-334829D01*
Y-334862D01*
Y-334894D01*
Y-334926D01*
Y-334959D01*
Y-334991D01*
Y-335023D01*
Y-335055D01*
Y-335087D01*
Y-335120D01*
Y-335152D01*
Y-335184D01*
Y-335217D01*
Y-335249D01*
Y-335281D01*
Y-335313D01*
Y-335346D01*
Y-335378D01*
Y-335410D01*
Y-335442D01*
Y-335475D01*
Y-335507D01*
Y-335539D01*
Y-335572D01*
Y-335604D01*
Y-335636D01*
Y-335668D01*
Y-335700D01*
Y-335733D01*
Y-335765D01*
Y-335797D01*
Y-335830D01*
Y-335862D01*
Y-335894D01*
Y-335926D01*
Y-335959D01*
Y-335991D01*
Y-336023D01*
Y-336055D01*
Y-336088D01*
Y-336120D01*
Y-336152D01*
Y-336184D01*
Y-336217D01*
Y-336249D01*
Y-336281D01*
Y-336314D01*
Y-336346D01*
Y-336378D01*
Y-336410D01*
Y-336442D01*
Y-336475D01*
Y-336507D01*
Y-336539D01*
Y-336572D01*
Y-336604D01*
Y-336636D01*
Y-336668D01*
Y-336701D01*
Y-336733D01*
Y-336765D01*
Y-336797D01*
Y-336830D01*
Y-336862D01*
Y-336894D01*
Y-336927D01*
Y-336959D01*
Y-336991D01*
Y-337023D01*
Y-337055D01*
Y-337088D01*
Y-337120D01*
Y-337152D01*
Y-337185D01*
Y-337217D01*
Y-337249D01*
Y-337281D01*
Y-337314D01*
Y-337346D01*
Y-337378D01*
Y-337410D01*
Y-337443D01*
Y-337475D01*
Y-337507D01*
Y-337539D01*
Y-337572D01*
Y-337604D01*
Y-337636D01*
Y-337668D01*
Y-337701D01*
Y-337733D01*
Y-337765D01*
Y-337797D01*
Y-337830D01*
Y-337862D01*
Y-337894D01*
Y-337927D01*
Y-337959D01*
Y-337991D01*
Y-338023D01*
Y-338056D01*
Y-338088D01*
Y-338120D01*
Y-338152D01*
Y-338185D01*
Y-338217D01*
Y-338249D01*
Y-338281D01*
Y-338314D01*
Y-338346D01*
Y-338378D01*
Y-338410D01*
Y-338443D01*
Y-338475D01*
Y-338507D01*
Y-338540D01*
Y-338572D01*
Y-338604D01*
Y-338636D01*
Y-338669D01*
Y-338701D01*
Y-338733D01*
Y-338765D01*
Y-338798D01*
Y-338830D01*
Y-338862D01*
Y-338894D01*
Y-338927D01*
Y-338959D01*
Y-338991D01*
Y-339023D01*
Y-339056D01*
Y-339088D01*
Y-339120D01*
Y-339153D01*
Y-339185D01*
Y-339217D01*
Y-339249D01*
Y-339282D01*
Y-339314D01*
Y-339346D01*
Y-339378D01*
Y-339411D01*
Y-339443D01*
Y-339475D01*
Y-339507D01*
Y-339540D01*
Y-339572D01*
Y-339604D01*
Y-339636D01*
Y-339669D01*
Y-339701D01*
Y-339733D01*
Y-339766D01*
Y-339798D01*
Y-339830D01*
Y-339862D01*
Y-339895D01*
Y-339927D01*
Y-339959D01*
Y-339991D01*
Y-340024D01*
Y-340056D01*
Y-340088D01*
Y-340120D01*
Y-340153D01*
Y-340185D01*
Y-340217D01*
Y-340249D01*
Y-340268D01*
X365450D01*
Y-340249D01*
Y-340217D01*
Y-340185D01*
Y-340153D01*
Y-340120D01*
Y-340088D01*
Y-340056D01*
Y-340024D01*
Y-339991D01*
Y-339959D01*
Y-339927D01*
Y-339895D01*
Y-339862D01*
Y-339830D01*
Y-339798D01*
Y-339766D01*
Y-339733D01*
Y-339701D01*
Y-339669D01*
Y-339636D01*
Y-339604D01*
Y-339572D01*
Y-339540D01*
Y-339507D01*
Y-339475D01*
Y-339443D01*
Y-339411D01*
Y-339378D01*
Y-339346D01*
D01*
Y-339314D01*
Y-339282D01*
Y-339249D01*
Y-339217D01*
Y-339185D01*
Y-339153D01*
Y-339120D01*
Y-339088D01*
Y-339056D01*
Y-339023D01*
Y-338991D01*
Y-338959D01*
Y-338927D01*
Y-338894D01*
Y-338862D01*
Y-338830D01*
Y-338798D01*
Y-338765D01*
Y-338733D01*
Y-338701D01*
Y-338669D01*
Y-338636D01*
Y-338604D01*
Y-338572D01*
Y-338540D01*
Y-338507D01*
Y-338475D01*
Y-338443D01*
Y-338410D01*
Y-338378D01*
Y-338346D01*
Y-338314D01*
Y-338281D01*
Y-338249D01*
Y-338217D01*
Y-338185D01*
Y-338152D01*
Y-338120D01*
Y-338088D01*
Y-338056D01*
Y-338023D01*
Y-337991D01*
Y-337959D01*
Y-337927D01*
Y-337894D01*
Y-337862D01*
Y-337830D01*
Y-337797D01*
Y-337765D01*
Y-337733D01*
Y-337701D01*
Y-337668D01*
Y-337636D01*
Y-337604D01*
Y-337572D01*
Y-337539D01*
Y-337507D01*
Y-337475D01*
Y-337443D01*
Y-337410D01*
Y-337378D01*
Y-337346D01*
Y-337314D01*
Y-337281D01*
Y-337249D01*
Y-337217D01*
Y-337185D01*
Y-337152D01*
Y-337120D01*
Y-337088D01*
Y-337055D01*
Y-337023D01*
Y-336991D01*
Y-336959D01*
Y-336927D01*
Y-336894D01*
Y-336862D01*
Y-336830D01*
Y-336797D01*
Y-336765D01*
Y-336733D01*
Y-336701D01*
Y-336668D01*
Y-336636D01*
Y-336604D01*
Y-336572D01*
Y-336539D01*
Y-336507D01*
Y-336475D01*
Y-336442D01*
Y-336410D01*
Y-336378D01*
Y-336346D01*
Y-336314D01*
Y-336281D01*
Y-336249D01*
Y-336217D01*
Y-336184D01*
Y-336152D01*
Y-336120D01*
Y-336088D01*
D01*
Y-336055D01*
Y-336023D01*
Y-335991D01*
Y-335959D01*
Y-335926D01*
Y-335894D01*
Y-335862D01*
Y-335830D01*
Y-335797D01*
Y-335765D01*
Y-335733D01*
Y-335700D01*
Y-335668D01*
Y-335636D01*
Y-335604D01*
Y-335572D01*
Y-335539D01*
Y-335507D01*
Y-335475D01*
Y-335442D01*
Y-335410D01*
Y-335378D01*
Y-335346D01*
Y-335313D01*
Y-335281D01*
Y-335249D01*
Y-335217D01*
Y-335184D01*
Y-335152D01*
Y-335120D01*
Y-335087D01*
Y-335055D01*
Y-335023D01*
Y-334991D01*
Y-334959D01*
Y-334926D01*
Y-334894D01*
Y-334862D01*
Y-334829D01*
Y-334797D01*
Y-334765D01*
Y-334733D01*
Y-334700D01*
Y-334668D01*
Y-334636D01*
Y-334604D01*
Y-334571D01*
Y-334539D01*
Y-334507D01*
Y-334474D01*
Y-334442D01*
Y-334410D01*
Y-334378D01*
Y-334346D01*
Y-334313D01*
Y-334281D01*
Y-334249D01*
Y-334216D01*
Y-334184D01*
Y-334152D01*
Y-334120D01*
Y-334087D01*
Y-334055D01*
Y-334037D01*
D02*
G37*
G36*
X363274D02*
X358702D01*
Y-334055D01*
Y-334087D01*
Y-334120D01*
Y-334152D01*
Y-334184D01*
Y-334216D01*
Y-334249D01*
Y-334281D01*
Y-334313D01*
Y-334346D01*
Y-334378D01*
Y-334410D01*
Y-334442D01*
Y-334474D01*
Y-334507D01*
Y-334539D01*
Y-334571D01*
Y-334604D01*
Y-334636D01*
Y-334668D01*
Y-334700D01*
Y-334733D01*
Y-334765D01*
Y-334797D01*
Y-334829D01*
Y-334862D01*
Y-334894D01*
Y-334926D01*
Y-334959D01*
Y-334977D01*
X360012D01*
X360064Y-334981D01*
X360115Y-334991D01*
X360165Y-335008D01*
X360212Y-335031D01*
X360256Y-335060D01*
X360295Y-335094D01*
X360310Y-335112D01*
X360327Y-335127D01*
X360342Y-335144D01*
X360359Y-335159D01*
X360394Y-335198D01*
X360423Y-335242D01*
X360446Y-335289D01*
X360449Y-335297D01*
X360455Y-335307D01*
X360479Y-335353D01*
X360495Y-335403D01*
X360506Y-335455D01*
X360509Y-335507D01*
Y-335539D01*
Y-335572D01*
Y-335604D01*
Y-335636D01*
Y-335668D01*
Y-335700D01*
Y-335733D01*
Y-335765D01*
Y-335797D01*
Y-335830D01*
Y-335862D01*
Y-335894D01*
Y-335926D01*
Y-335959D01*
Y-335991D01*
Y-336023D01*
Y-336055D01*
Y-336088D01*
Y-336120D01*
Y-336152D01*
Y-336184D01*
Y-336217D01*
Y-336249D01*
Y-336281D01*
Y-336314D01*
Y-336346D01*
Y-336378D01*
Y-336410D01*
Y-336442D01*
Y-336475D01*
Y-336507D01*
Y-336539D01*
Y-336572D01*
Y-336604D01*
Y-336636D01*
Y-336668D01*
Y-336701D01*
Y-336733D01*
Y-336765D01*
Y-336797D01*
Y-336830D01*
Y-336862D01*
Y-336894D01*
Y-336927D01*
Y-336959D01*
Y-336991D01*
Y-337023D01*
Y-337055D01*
Y-337088D01*
Y-337120D01*
Y-337152D01*
Y-337185D01*
Y-337217D01*
Y-337249D01*
Y-337281D01*
Y-337314D01*
Y-337346D01*
Y-337378D01*
Y-337410D01*
Y-337443D01*
Y-337475D01*
Y-337507D01*
Y-337539D01*
Y-337572D01*
Y-337604D01*
Y-337636D01*
Y-337668D01*
Y-337701D01*
Y-337733D01*
Y-337765D01*
Y-337797D01*
Y-337830D01*
Y-337862D01*
Y-337894D01*
Y-337927D01*
Y-337959D01*
Y-337991D01*
Y-338023D01*
Y-338056D01*
Y-338088D01*
Y-338120D01*
Y-338152D01*
Y-338185D01*
Y-338217D01*
Y-338249D01*
Y-338281D01*
Y-338314D01*
Y-338346D01*
Y-338378D01*
Y-338410D01*
Y-338443D01*
Y-338475D01*
Y-338507D01*
Y-338540D01*
Y-338572D01*
Y-338604D01*
Y-338636D01*
Y-338669D01*
Y-338701D01*
Y-338733D01*
Y-338765D01*
Y-338798D01*
Y-338830D01*
Y-338862D01*
Y-338894D01*
Y-338927D01*
Y-338959D01*
Y-338991D01*
Y-339023D01*
Y-339056D01*
Y-339088D01*
Y-339120D01*
Y-339153D01*
Y-339185D01*
Y-339217D01*
Y-339249D01*
Y-339282D01*
Y-339314D01*
Y-339346D01*
Y-339378D01*
Y-339411D01*
Y-339443D01*
Y-339475D01*
Y-339507D01*
Y-339540D01*
Y-339572D01*
Y-339604D01*
Y-339636D01*
Y-339669D01*
Y-339701D01*
Y-339733D01*
Y-339766D01*
Y-339798D01*
Y-339830D01*
Y-339862D01*
Y-339895D01*
Y-339927D01*
Y-339959D01*
Y-339991D01*
Y-340024D01*
Y-340056D01*
Y-340088D01*
Y-340120D01*
Y-340153D01*
Y-340185D01*
Y-340217D01*
Y-340249D01*
Y-340268D01*
X361482D01*
Y-340249D01*
Y-340217D01*
Y-340185D01*
Y-340153D01*
Y-340120D01*
Y-340088D01*
Y-340056D01*
Y-340024D01*
Y-339991D01*
Y-339959D01*
Y-339927D01*
Y-339895D01*
Y-339862D01*
Y-339830D01*
Y-339798D01*
Y-339766D01*
Y-339733D01*
Y-339701D01*
Y-339669D01*
Y-339636D01*
Y-339604D01*
Y-339572D01*
Y-339540D01*
Y-339507D01*
Y-339475D01*
Y-339443D01*
Y-339411D01*
Y-339378D01*
Y-339346D01*
Y-339314D01*
Y-339282D01*
Y-339249D01*
Y-339217D01*
Y-339185D01*
Y-339153D01*
Y-339120D01*
Y-339088D01*
Y-339056D01*
Y-339023D01*
Y-338991D01*
Y-338959D01*
Y-338927D01*
Y-338894D01*
Y-338862D01*
Y-338830D01*
Y-338798D01*
Y-338765D01*
Y-338733D01*
Y-338701D01*
Y-338669D01*
Y-338636D01*
Y-338604D01*
Y-338572D01*
Y-338540D01*
Y-338507D01*
Y-338475D01*
Y-338443D01*
Y-338410D01*
Y-338378D01*
Y-338346D01*
Y-338314D01*
Y-338281D01*
Y-338249D01*
Y-338217D01*
Y-338185D01*
Y-338152D01*
Y-338120D01*
Y-338088D01*
Y-338056D01*
Y-338023D01*
Y-337991D01*
Y-337959D01*
Y-337927D01*
Y-337894D01*
Y-337862D01*
Y-337830D01*
Y-337797D01*
Y-337765D01*
Y-337733D01*
Y-337701D01*
Y-337668D01*
Y-337636D01*
Y-337604D01*
Y-337572D01*
Y-337539D01*
Y-337507D01*
Y-337475D01*
Y-337443D01*
Y-337410D01*
Y-337378D01*
Y-337346D01*
Y-337314D01*
Y-337281D01*
Y-337249D01*
Y-337217D01*
Y-337185D01*
Y-337152D01*
Y-337120D01*
Y-337088D01*
Y-337055D01*
Y-337023D01*
Y-336991D01*
Y-336959D01*
Y-336927D01*
Y-336894D01*
Y-336862D01*
Y-336830D01*
Y-336797D01*
Y-336765D01*
Y-336733D01*
Y-336701D01*
Y-336668D01*
Y-336636D01*
Y-336604D01*
Y-336572D01*
Y-336539D01*
Y-336507D01*
Y-336475D01*
Y-336442D01*
Y-336410D01*
Y-336378D01*
Y-336346D01*
Y-336314D01*
Y-336281D01*
Y-336249D01*
Y-336217D01*
Y-336184D01*
Y-336152D01*
Y-336120D01*
Y-336088D01*
D01*
Y-336055D01*
Y-336023D01*
Y-335991D01*
Y-335959D01*
Y-335926D01*
Y-335894D01*
Y-335862D01*
Y-335830D01*
Y-335797D01*
Y-335765D01*
Y-335733D01*
Y-335700D01*
Y-335668D01*
Y-335636D01*
Y-335604D01*
Y-335572D01*
Y-335539D01*
Y-335507D01*
Y-335475D01*
Y-335442D01*
X361485Y-335390D01*
X361495Y-335339D01*
X361512Y-335289D01*
X361536Y-335242D01*
X361565Y-335198D01*
X361599Y-335159D01*
X361616Y-335144D01*
X361631Y-335127D01*
X361649Y-335112D01*
X361664Y-335094D01*
X361703Y-335060D01*
X361747Y-335031D01*
X361794Y-335008D01*
X361843Y-334991D01*
X361895Y-334981D01*
X361947Y-334977D01*
X363288D01*
Y-334959D01*
Y-334926D01*
Y-334894D01*
Y-334862D01*
Y-334829D01*
Y-334797D01*
Y-334765D01*
Y-334733D01*
Y-334700D01*
Y-334668D01*
Y-334636D01*
Y-334604D01*
Y-334571D01*
Y-334539D01*
Y-334507D01*
Y-334474D01*
Y-334442D01*
Y-334410D01*
Y-334378D01*
Y-334346D01*
Y-334313D01*
Y-334281D01*
Y-334249D01*
Y-334216D01*
Y-334184D01*
Y-334152D01*
Y-334120D01*
Y-334087D01*
Y-334055D01*
Y-334042D01*
X363278Y-334038D01*
X363274Y-334037D01*
D02*
G37*
G36*
X356191Y-341298D02*
X356168Y-341332D01*
X356147Y-341356D01*
X356132Y-341385D01*
X356103Y-341429D01*
X356069Y-341469D01*
X356051Y-341484D01*
X356036Y-341501D01*
X356019Y-341516D01*
X356004Y-341533D01*
X355987Y-341548D01*
X355972Y-341565D01*
X355955Y-341580D01*
X355940Y-341598D01*
X355922Y-341613D01*
X355907Y-341630D01*
X355890Y-341645D01*
X355875Y-341662D01*
X355858Y-341677D01*
X355843Y-341694D01*
X355826Y-341709D01*
X355810Y-341727D01*
X355771Y-341761D01*
X355728Y-341790D01*
X355698Y-341805D01*
X355685Y-341816D01*
X356191D01*
Y-341798D01*
Y-341766D01*
Y-341734D01*
Y-341701D01*
Y-341669D01*
Y-341637D01*
Y-341604D01*
Y-341572D01*
Y-341540D01*
Y-341508D01*
Y-341475D01*
Y-341443D01*
Y-341411D01*
Y-341379D01*
Y-341346D01*
Y-341314D01*
Y-341298D01*
D02*
G37*
G36*
Y-343425D02*
X355640D01*
X355640Y-343425D01*
X355648Y-343428D01*
X355695Y-343451D01*
X355739Y-343480D01*
X355778Y-343515D01*
X355793Y-343532D01*
X355795Y-343533D01*
X355823Y-343547D01*
X355824Y-343548D01*
X355868Y-343577D01*
X355907Y-343612D01*
X355922Y-343629D01*
X355940Y-343644D01*
X355955Y-343661D01*
X355972Y-343676D01*
X355987Y-343693D01*
X356004Y-343708D01*
X356039Y-343748D01*
X356068Y-343791D01*
X356082Y-343821D01*
X356084Y-343822D01*
X356101Y-343837D01*
X356135Y-343877D01*
X356165Y-343920D01*
X356188Y-343967D01*
X356190Y-343975D01*
X356191Y-343976D01*
Y-343959D01*
Y-343927D01*
Y-343895D01*
Y-343863D01*
Y-343830D01*
Y-343798D01*
Y-343766D01*
Y-343734D01*
Y-343701D01*
Y-343669D01*
Y-343637D01*
Y-343605D01*
Y-343572D01*
Y-343540D01*
Y-343508D01*
Y-343476D01*
Y-343443D01*
Y-343425D01*
D02*
G37*
G36*
X374953Y-341650D02*
X374855D01*
X374845Y-341662D01*
X374828Y-341677D01*
X374820Y-341686D01*
X374813Y-341694D01*
X374796Y-341709D01*
X374780Y-341727D01*
X374763Y-341742D01*
X374761Y-341744D01*
X374748Y-341759D01*
X374731Y-341774D01*
X374716Y-341791D01*
X374699Y-341806D01*
X374684Y-341823D01*
X374666Y-341838D01*
X374651Y-341856D01*
X374634Y-341871D01*
X374619Y-341888D01*
X374602Y-341903D01*
X374587Y-341920D01*
X374570Y-341935D01*
X374566Y-341939D01*
X374555Y-341952D01*
X374537Y-341967D01*
X374522Y-341985D01*
X374505Y-342000D01*
X374490Y-342017D01*
X374473Y-342032D01*
X374458Y-342049D01*
X374441Y-342064D01*
X374426Y-342081D01*
X374408Y-342096D01*
X374393Y-342114D01*
X374376Y-342129D01*
X374361Y-342146D01*
X374344Y-342161D01*
X374329Y-342178D01*
X374312Y-342193D01*
X374296Y-342211D01*
X374280Y-342225D01*
X374279Y-342226D01*
X374264Y-342243D01*
X374247Y-342258D01*
X374232Y-342275D01*
X374215Y-342290D01*
X374200Y-342307D01*
X374183Y-342322D01*
X374183Y-342322D01*
X374167Y-342339D01*
X374150Y-342355D01*
X374135Y-342372D01*
X374118Y-342387D01*
X374103Y-342404D01*
X374086Y-342419D01*
X374082Y-342423D01*
X374077Y-342429D01*
X374562D01*
X374614Y-342433D01*
X374665Y-342443D01*
X374715Y-342460D01*
X374762Y-342483D01*
X374805Y-342512D01*
X374845Y-342547D01*
X374880Y-342586D01*
X374909Y-342630D01*
X374932Y-342677D01*
X374949Y-342727D01*
X374959Y-342778D01*
X374962Y-342830D01*
Y-342863D01*
Y-342895D01*
Y-342927D01*
Y-342959D01*
Y-342992D01*
Y-343024D01*
Y-343056D01*
Y-343089D01*
Y-343121D01*
Y-343153D01*
Y-343185D01*
Y-343217D01*
Y-343250D01*
Y-343282D01*
Y-343314D01*
Y-343347D01*
Y-343379D01*
Y-343411D01*
Y-343443D01*
Y-343476D01*
Y-343508D01*
Y-343540D01*
Y-343572D01*
Y-343605D01*
Y-343637D01*
Y-343669D01*
Y-343701D01*
Y-343734D01*
Y-343766D01*
Y-343798D01*
Y-343830D01*
Y-343863D01*
Y-343895D01*
Y-343927D01*
Y-343959D01*
Y-343992D01*
Y-344024D01*
Y-344056D01*
Y-344089D01*
Y-344121D01*
Y-344153D01*
Y-344185D01*
Y-344218D01*
Y-344250D01*
Y-344282D01*
Y-344314D01*
Y-344347D01*
Y-344379D01*
Y-344411D01*
Y-344443D01*
Y-344476D01*
Y-344508D01*
Y-344540D01*
Y-344572D01*
Y-344605D01*
X374959Y-344657D01*
X374949Y-344708D01*
X374932Y-344758D01*
X374909Y-344805D01*
X374880Y-344849D01*
X374845Y-344888D01*
X374805Y-344923D01*
X374762Y-344952D01*
X374715Y-344975D01*
X374665Y-344992D01*
X374614Y-345002D01*
X374562Y-345006D01*
X372206D01*
X372154Y-345002D01*
X372103Y-344992D01*
X372053Y-344975D01*
X372006Y-344952D01*
X371962Y-344923D01*
X371923Y-344888D01*
X371888Y-344849D01*
X371860Y-344806D01*
X371860Y-344807D01*
X371845Y-344824D01*
X371827Y-344839D01*
X371812Y-344856D01*
X371795Y-344871D01*
X371780Y-344888D01*
X371763Y-344903D01*
X371748Y-344920D01*
X371731Y-344935D01*
X371716Y-344953D01*
X371698Y-344968D01*
X371683Y-344985D01*
X371666Y-345000D01*
X371651Y-345017D01*
X371634Y-345032D01*
X371619Y-345050D01*
X371602Y-345065D01*
X371586Y-345082D01*
X371569Y-345097D01*
X371554Y-345114D01*
X371537Y-345129D01*
X371522Y-345146D01*
X371505Y-345161D01*
X371490Y-345179D01*
X371473Y-345194D01*
X371458Y-345211D01*
X371440Y-345226D01*
X371425Y-345243D01*
X371408Y-345258D01*
X371393Y-345275D01*
X371376Y-345290D01*
X371361Y-345308D01*
X371343Y-345323D01*
X371328Y-345340D01*
X371311Y-345355D01*
X371296Y-345372D01*
X371279Y-345387D01*
X371264Y-345404D01*
X371247Y-345420D01*
X371232Y-345437D01*
X371214Y-345452D01*
X371199Y-345469D01*
X371182Y-345484D01*
X371167Y-345501D01*
X371150Y-345516D01*
X371135Y-345533D01*
X371118Y-345549D01*
X371103Y-345566D01*
X371085Y-345581D01*
X371070Y-345598D01*
X371053Y-345613D01*
X371038Y-345630D01*
X371021Y-345645D01*
X371006Y-345662D01*
X370989Y-345677D01*
X370973Y-345695D01*
X370934Y-345729D01*
X370890Y-345759D01*
X370861Y-345773D01*
X370860Y-345774D01*
X370845Y-345792D01*
X370833Y-345802D01*
Y-345831D01*
Y-345863D01*
Y-345895D01*
Y-345928D01*
Y-345960D01*
Y-345992D01*
Y-346024D01*
Y-346057D01*
Y-346089D01*
Y-346121D01*
Y-346153D01*
Y-346186D01*
Y-346218D01*
Y-346250D01*
Y-346282D01*
Y-346315D01*
Y-346347D01*
Y-346379D01*
Y-346411D01*
Y-346444D01*
Y-346476D01*
Y-346508D01*
Y-346540D01*
Y-346573D01*
Y-346605D01*
Y-346637D01*
Y-346670D01*
Y-346702D01*
Y-346734D01*
Y-346766D01*
Y-346799D01*
Y-346831D01*
Y-346863D01*
Y-346895D01*
Y-346928D01*
Y-346960D01*
Y-346992D01*
Y-347024D01*
Y-347057D01*
Y-347089D01*
Y-347121D01*
Y-347153D01*
Y-347186D01*
Y-347218D01*
Y-347250D01*
Y-347283D01*
Y-347315D01*
Y-347347D01*
Y-347379D01*
Y-347411D01*
Y-347444D01*
Y-347476D01*
Y-347508D01*
Y-347541D01*
Y-347573D01*
Y-347605D01*
Y-347637D01*
Y-347670D01*
Y-347702D01*
Y-347734D01*
Y-347766D01*
Y-347799D01*
Y-347831D01*
Y-347863D01*
Y-347882D01*
X371806D01*
Y-347863D01*
Y-347831D01*
Y-347799D01*
Y-347766D01*
Y-347734D01*
Y-347702D01*
Y-347670D01*
Y-347637D01*
Y-347605D01*
Y-347573D01*
Y-347541D01*
Y-347508D01*
Y-347476D01*
Y-347444D01*
Y-347411D01*
Y-347379D01*
Y-347347D01*
Y-347315D01*
Y-347283D01*
Y-347250D01*
Y-347218D01*
Y-347186D01*
Y-347153D01*
Y-347121D01*
Y-347089D01*
Y-347057D01*
Y-347024D01*
Y-346992D01*
Y-346960D01*
Y-346928D01*
Y-346895D01*
Y-346863D01*
Y-346831D01*
Y-346799D01*
Y-346766D01*
Y-346734D01*
Y-346702D01*
Y-346670D01*
Y-346637D01*
Y-346605D01*
Y-346573D01*
Y-346540D01*
Y-346508D01*
Y-346476D01*
Y-346444D01*
Y-346411D01*
Y-346379D01*
Y-346347D01*
Y-346315D01*
Y-346282D01*
Y-346250D01*
Y-346218D01*
X371809Y-346165D01*
X371819Y-346114D01*
X371836Y-346064D01*
X371859Y-346017D01*
X371866Y-346008D01*
X371868Y-346000D01*
X371891Y-345953D01*
X371921Y-345909D01*
X371955Y-345870D01*
X371995Y-345835D01*
X372038Y-345806D01*
X372085Y-345783D01*
X372093Y-345780D01*
X372095Y-345779D01*
X372103Y-345774D01*
X372150Y-345751D01*
X372199Y-345734D01*
X372251Y-345724D01*
X372303Y-345720D01*
X374465D01*
X374517Y-345724D01*
X374569Y-345734D01*
X374618Y-345751D01*
X374665Y-345774D01*
X374675Y-345780D01*
X374683Y-345783D01*
X374730Y-345806D01*
X374773Y-345835D01*
X374813Y-345870D01*
X374847Y-345909D01*
X374876Y-345953D01*
X374900Y-346000D01*
X374902Y-346008D01*
X374909Y-346017D01*
X374932Y-346064D01*
X374949Y-346114D01*
X374959Y-346165D01*
X374962Y-346218D01*
Y-346250D01*
Y-346282D01*
Y-346315D01*
Y-346347D01*
Y-346379D01*
Y-346411D01*
Y-346444D01*
Y-346476D01*
Y-346508D01*
Y-346540D01*
Y-346573D01*
Y-346605D01*
Y-346637D01*
Y-346670D01*
Y-346702D01*
Y-346734D01*
Y-346766D01*
Y-346799D01*
Y-346831D01*
Y-346863D01*
Y-346895D01*
Y-346928D01*
Y-346960D01*
Y-346992D01*
Y-347024D01*
Y-347057D01*
Y-347089D01*
Y-347121D01*
Y-347153D01*
Y-347186D01*
Y-347218D01*
Y-347250D01*
Y-347283D01*
Y-347315D01*
Y-347347D01*
Y-347379D01*
Y-347411D01*
Y-347444D01*
Y-347476D01*
Y-347508D01*
Y-347541D01*
Y-347573D01*
Y-347605D01*
Y-347637D01*
Y-347670D01*
Y-347702D01*
Y-347734D01*
Y-347766D01*
Y-347799D01*
Y-347831D01*
Y-347863D01*
Y-347882D01*
X375935D01*
Y-347863D01*
Y-347831D01*
Y-347799D01*
Y-347766D01*
Y-347734D01*
Y-347702D01*
Y-347670D01*
Y-347637D01*
Y-347605D01*
Y-347573D01*
Y-347541D01*
Y-347508D01*
Y-347476D01*
Y-347444D01*
Y-347411D01*
Y-347379D01*
Y-347347D01*
Y-347315D01*
Y-347283D01*
Y-347250D01*
Y-347218D01*
Y-347186D01*
Y-347153D01*
Y-347121D01*
Y-347089D01*
Y-347057D01*
Y-347024D01*
Y-346992D01*
Y-346960D01*
Y-346928D01*
Y-346895D01*
Y-346863D01*
Y-346831D01*
Y-346799D01*
Y-346766D01*
Y-346734D01*
Y-346702D01*
Y-346670D01*
Y-346637D01*
Y-346605D01*
Y-346573D01*
Y-346540D01*
Y-346508D01*
Y-346476D01*
Y-346444D01*
Y-346411D01*
Y-346379D01*
Y-346347D01*
Y-346315D01*
Y-346282D01*
Y-346250D01*
Y-346218D01*
Y-346186D01*
Y-346153D01*
Y-346121D01*
Y-346089D01*
Y-346057D01*
Y-346024D01*
Y-345992D01*
Y-345960D01*
Y-345928D01*
Y-345895D01*
Y-345863D01*
Y-345831D01*
Y-345798D01*
Y-345766D01*
Y-345734D01*
Y-345702D01*
Y-345669D01*
Y-345637D01*
Y-345605D01*
Y-345573D01*
Y-345540D01*
Y-345508D01*
Y-345476D01*
Y-345444D01*
Y-345411D01*
Y-345379D01*
Y-345347D01*
Y-345315D01*
Y-345282D01*
Y-345250D01*
Y-345218D01*
Y-345185D01*
Y-345153D01*
Y-345121D01*
Y-345089D01*
Y-345056D01*
Y-345024D01*
Y-344992D01*
D01*
Y-344960D01*
Y-344927D01*
Y-344895D01*
Y-344863D01*
D01*
Y-344831D01*
Y-344798D01*
Y-344766D01*
Y-344734D01*
Y-344702D01*
Y-344669D01*
Y-344637D01*
Y-344605D01*
Y-344572D01*
Y-344540D01*
Y-344508D01*
Y-344476D01*
Y-344443D01*
Y-344411D01*
Y-344379D01*
Y-344347D01*
Y-344314D01*
Y-344282D01*
Y-344250D01*
Y-344218D01*
Y-344185D01*
Y-344153D01*
Y-344121D01*
Y-344089D01*
Y-344056D01*
Y-344024D01*
Y-343992D01*
Y-343959D01*
Y-343927D01*
Y-343895D01*
Y-343863D01*
Y-343830D01*
Y-343798D01*
Y-343766D01*
Y-343734D01*
Y-343701D01*
Y-343669D01*
Y-343637D01*
Y-343605D01*
Y-343572D01*
Y-343540D01*
Y-343508D01*
Y-343476D01*
Y-343443D01*
Y-343411D01*
Y-343379D01*
Y-343347D01*
Y-343314D01*
Y-343282D01*
Y-343250D01*
Y-343217D01*
Y-343185D01*
Y-343153D01*
Y-343121D01*
Y-343089D01*
Y-343056D01*
Y-343024D01*
Y-342992D01*
Y-342959D01*
Y-342927D01*
Y-342895D01*
Y-342863D01*
Y-342830D01*
Y-342798D01*
Y-342766D01*
Y-342734D01*
Y-342701D01*
Y-342669D01*
Y-342637D01*
Y-342633D01*
X375933Y-342629D01*
X375916Y-342579D01*
X375906Y-342528D01*
X375905Y-342516D01*
X375905Y-342508D01*
X375901Y-342500D01*
X375890Y-342467D01*
X375876Y-342451D01*
X375859Y-342436D01*
X375844Y-342419D01*
X375827Y-342404D01*
X375815Y-342391D01*
X375812Y-342387D01*
X375794Y-342372D01*
X375790Y-342367D01*
X375779Y-342355D01*
X375762Y-342339D01*
X375747Y-342322D01*
X375730Y-342307D01*
X375718Y-342294D01*
X375715Y-342290D01*
X375698Y-342275D01*
X375682Y-342258D01*
X375665Y-342243D01*
X375650Y-342226D01*
X375633Y-342211D01*
X375632Y-342209D01*
X375618Y-342193D01*
X375601Y-342178D01*
X375586Y-342161D01*
X375569Y-342146D01*
X375553Y-342129D01*
X375536Y-342114D01*
X375530Y-342107D01*
X375521Y-342096D01*
X375504Y-342081D01*
X375489Y-342064D01*
X375472Y-342049D01*
X375471Y-342048D01*
X375457Y-342032D01*
X375457Y-342032D01*
X375440Y-342017D01*
X375433Y-342010D01*
X375424Y-342000D01*
X375407Y-341985D01*
X375392Y-341967D01*
X375375Y-341952D01*
X375360Y-341935D01*
X375343Y-341920D01*
X375328Y-341903D01*
X375310Y-341888D01*
X375295Y-341871D01*
X375278Y-341856D01*
X375263Y-341839D01*
X375246Y-341823D01*
X375231Y-341806D01*
X375214Y-341791D01*
X375199Y-341774D01*
X375181Y-341759D01*
X375166Y-341742D01*
X375149Y-341727D01*
X375138Y-341713D01*
X375134Y-341709D01*
X375132Y-341708D01*
X375103Y-341693D01*
X375094Y-341687D01*
X375086Y-341684D01*
X375078Y-341681D01*
X375058Y-341679D01*
X375006Y-341669D01*
X374957Y-341652D01*
X374953Y-341650D01*
D02*
G37*
G36*
X372727Y-330198D02*
X372704D01*
Y-330216D01*
Y-330248D01*
Y-330280D01*
Y-330313D01*
Y-330345D01*
Y-330377D01*
Y-330410D01*
Y-330442D01*
Y-330474D01*
Y-330506D01*
Y-330539D01*
Y-330571D01*
Y-330603D01*
Y-330635D01*
Y-330668D01*
Y-330700D01*
Y-330732D01*
Y-330764D01*
Y-330797D01*
Y-330829D01*
Y-330861D01*
Y-330893D01*
Y-330926D01*
Y-330958D01*
Y-330990D01*
Y-331023D01*
Y-331055D01*
Y-331087D01*
Y-331119D01*
Y-331152D01*
Y-331184D01*
Y-331216D01*
Y-331248D01*
Y-331281D01*
Y-331313D01*
Y-331345D01*
Y-331377D01*
Y-331410D01*
Y-331442D01*
Y-331474D01*
Y-331506D01*
Y-331539D01*
Y-331571D01*
Y-331603D01*
Y-331635D01*
Y-331668D01*
Y-331700D01*
Y-331732D01*
Y-331765D01*
Y-331797D01*
Y-331829D01*
Y-331861D01*
Y-331894D01*
Y-331926D01*
Y-331958D01*
Y-331990D01*
Y-332023D01*
Y-332055D01*
Y-332087D01*
Y-332119D01*
Y-332152D01*
Y-332184D01*
Y-332216D01*
Y-332248D01*
Y-332281D01*
Y-332313D01*
Y-332345D01*
Y-332378D01*
Y-332410D01*
Y-332442D01*
Y-332474D01*
Y-332507D01*
Y-332539D01*
Y-332571D01*
Y-332603D01*
Y-332636D01*
Y-332668D01*
Y-332700D01*
Y-332732D01*
Y-332765D01*
Y-332797D01*
Y-332829D01*
Y-332861D01*
Y-332894D01*
Y-332926D01*
Y-332958D01*
Y-332991D01*
Y-333023D01*
Y-333055D01*
Y-333087D01*
Y-333120D01*
Y-333152D01*
Y-333184D01*
Y-333216D01*
Y-333249D01*
Y-333281D01*
Y-333313D01*
Y-333345D01*
Y-333378D01*
Y-333410D01*
Y-333442D01*
Y-333474D01*
Y-333507D01*
Y-333539D01*
Y-333571D01*
Y-333604D01*
Y-333636D01*
Y-333668D01*
Y-333700D01*
Y-333733D01*
Y-333765D01*
Y-333797D01*
Y-333829D01*
Y-333862D01*
Y-333894D01*
Y-333926D01*
Y-333958D01*
Y-333991D01*
Y-334023D01*
Y-334055D01*
Y-334087D01*
Y-334120D01*
Y-334152D01*
Y-334184D01*
Y-334216D01*
Y-334249D01*
Y-334281D01*
Y-334313D01*
Y-334346D01*
Y-334378D01*
Y-334410D01*
Y-334442D01*
Y-334474D01*
Y-334507D01*
Y-334539D01*
Y-334571D01*
Y-334604D01*
Y-334636D01*
Y-334668D01*
Y-334700D01*
Y-334733D01*
Y-334765D01*
Y-334797D01*
Y-334829D01*
Y-334862D01*
Y-334894D01*
Y-334926D01*
Y-334959D01*
Y-334991D01*
Y-335023D01*
Y-335055D01*
Y-335087D01*
Y-335120D01*
Y-335152D01*
Y-335184D01*
Y-335217D01*
Y-335249D01*
Y-335281D01*
Y-335313D01*
Y-335346D01*
Y-335378D01*
Y-335410D01*
Y-335442D01*
Y-335475D01*
Y-335507D01*
Y-335539D01*
Y-335572D01*
Y-335604D01*
Y-335636D01*
Y-335668D01*
Y-335700D01*
Y-335733D01*
Y-335765D01*
Y-335797D01*
Y-335830D01*
Y-335862D01*
Y-335894D01*
Y-335926D01*
Y-335959D01*
Y-335991D01*
Y-336023D01*
Y-336055D01*
Y-336088D01*
Y-336120D01*
Y-336152D01*
Y-336184D01*
Y-336217D01*
Y-336249D01*
Y-336281D01*
Y-336314D01*
Y-336346D01*
Y-336378D01*
Y-336410D01*
Y-336442D01*
Y-336475D01*
Y-336507D01*
Y-336539D01*
Y-336572D01*
Y-336604D01*
Y-336636D01*
Y-336668D01*
Y-336701D01*
Y-336733D01*
Y-336765D01*
Y-336797D01*
Y-336830D01*
Y-336862D01*
Y-336894D01*
Y-336927D01*
Y-336959D01*
Y-336991D01*
Y-337023D01*
Y-337055D01*
Y-337088D01*
Y-337120D01*
Y-337152D01*
Y-337185D01*
Y-337217D01*
Y-337249D01*
Y-337281D01*
Y-337314D01*
Y-337346D01*
Y-337378D01*
Y-337410D01*
Y-337443D01*
Y-337475D01*
Y-337507D01*
Y-337539D01*
Y-337572D01*
Y-337604D01*
Y-337636D01*
Y-337668D01*
Y-337701D01*
Y-337733D01*
Y-337765D01*
Y-337797D01*
Y-337830D01*
Y-337862D01*
Y-337894D01*
Y-337927D01*
Y-337959D01*
Y-337991D01*
Y-338023D01*
Y-338056D01*
D01*
Y-338088D01*
Y-338120D01*
Y-338152D01*
Y-338185D01*
Y-338217D01*
Y-338249D01*
Y-338281D01*
Y-338314D01*
Y-338346D01*
Y-338378D01*
Y-338410D01*
Y-338443D01*
Y-338475D01*
Y-338507D01*
Y-338540D01*
Y-338572D01*
Y-338604D01*
Y-338636D01*
Y-338669D01*
Y-338701D01*
Y-338733D01*
Y-338765D01*
Y-338798D01*
Y-338830D01*
Y-338862D01*
Y-338894D01*
Y-338927D01*
Y-338959D01*
Y-338991D01*
Y-339023D01*
Y-339056D01*
Y-339088D01*
Y-339120D01*
Y-339153D01*
Y-339185D01*
Y-339217D01*
Y-339249D01*
Y-339282D01*
Y-339314D01*
Y-339346D01*
D01*
Y-339378D01*
Y-339411D01*
Y-339443D01*
Y-339475D01*
Y-339507D01*
Y-339540D01*
Y-339572D01*
Y-339604D01*
Y-339636D01*
Y-339669D01*
Y-339701D01*
Y-339733D01*
Y-339766D01*
Y-339798D01*
Y-339830D01*
Y-339862D01*
Y-339895D01*
Y-339927D01*
Y-339959D01*
Y-339991D01*
Y-340024D01*
Y-340056D01*
Y-340088D01*
Y-340120D01*
Y-340153D01*
Y-340185D01*
Y-340217D01*
Y-340249D01*
Y-340282D01*
Y-340314D01*
Y-340346D01*
Y-340378D01*
Y-340411D01*
Y-340443D01*
Y-340475D01*
X372701Y-340528D01*
X372690Y-340579D01*
X372674Y-340629D01*
X372650Y-340676D01*
X372621Y-340719D01*
X372587Y-340759D01*
X372569Y-340774D01*
X372554Y-340791D01*
X372537Y-340806D01*
X372522Y-340823D01*
X372505Y-340838D01*
X372490Y-340856D01*
X372473Y-340871D01*
X372458Y-340888D01*
X372440Y-340903D01*
X372440Y-340903D01*
X372425Y-340920D01*
X372408Y-340935D01*
D01*
X372393Y-340952D01*
X372376Y-340967D01*
X372361Y-340985D01*
X372344Y-341000D01*
X372328Y-341017D01*
X372311Y-341032D01*
X372296Y-341049D01*
X372279Y-341064D01*
X372264Y-341081D01*
X372247Y-341096D01*
X372232Y-341114D01*
X372215Y-341129D01*
X372200Y-341146D01*
X372182Y-341161D01*
X372167Y-341178D01*
X372150Y-341193D01*
X372135Y-341210D01*
X372118Y-341226D01*
X372103Y-341243D01*
X372085Y-341258D01*
X372070Y-341275D01*
X372053Y-341290D01*
X372038Y-341307D01*
X371999Y-341342D01*
X371955Y-341371D01*
X371926Y-341385D01*
X371924Y-341387D01*
X371909Y-341404D01*
X371892Y-341419D01*
X371877Y-341436D01*
X371860Y-341451D01*
X371845Y-341469D01*
X371827Y-341483D01*
X371812Y-341501D01*
X371795Y-341516D01*
X371780Y-341533D01*
X371763Y-341548D01*
X371748Y-341565D01*
X371731Y-341580D01*
X371716Y-341598D01*
X371698Y-341613D01*
X371683Y-341630D01*
X371666Y-341645D01*
X371651Y-341662D01*
X371634Y-341677D01*
X371625Y-341687D01*
X371619Y-341694D01*
X371602Y-341709D01*
X371586Y-341727D01*
X371569Y-341742D01*
X371554Y-341759D01*
X371537Y-341774D01*
X371522Y-341791D01*
X371505Y-341806D01*
X371505Y-341806D01*
X371490Y-341823D01*
X371473Y-341838D01*
X371459Y-341854D01*
X371458Y-341856D01*
X371440Y-341871D01*
X371425Y-341888D01*
X371408Y-341903D01*
X371393Y-341920D01*
X371376Y-341935D01*
X371362Y-341951D01*
X371361Y-341952D01*
X371344Y-341967D01*
X371328Y-341985D01*
X371311Y-342000D01*
X371306Y-342005D01*
X371296Y-342017D01*
X371279Y-342032D01*
X371264Y-342049D01*
X371247Y-342064D01*
X371232Y-342081D01*
X371215Y-342096D01*
X371199Y-342114D01*
X371182Y-342129D01*
X371182Y-342129D01*
X371167Y-342146D01*
X371150Y-342161D01*
X371145Y-342167D01*
X371135Y-342178D01*
X371118Y-342193D01*
X371104Y-342209D01*
X371103Y-342211D01*
X371085Y-342226D01*
X371070Y-342243D01*
X371053Y-342258D01*
X371038Y-342275D01*
X371021Y-342290D01*
X371006Y-342307D01*
X370989Y-342322D01*
X370973Y-342339D01*
X370956Y-342355D01*
X370941Y-342372D01*
X370924Y-342387D01*
X370909Y-342404D01*
X370892Y-342419D01*
X370892Y-342419D01*
X370877Y-342436D01*
X370860Y-342451D01*
X370860Y-342451D01*
X370845Y-342469D01*
X370827Y-342484D01*
X370812Y-342501D01*
X370795Y-342516D01*
X370780Y-342533D01*
X370763Y-342548D01*
X370748Y-342565D01*
X370730Y-342580D01*
X370715Y-342598D01*
X370698Y-342613D01*
X370683Y-342630D01*
X370666Y-342645D01*
X370651Y-342662D01*
X370634Y-342677D01*
X370625Y-342687D01*
X370619Y-342694D01*
X370602Y-342709D01*
X370586Y-342727D01*
X370569Y-342742D01*
X370554Y-342759D01*
X370537Y-342774D01*
X370522Y-342791D01*
X370505Y-342806D01*
X370490Y-342824D01*
X370472Y-342839D01*
X370457Y-342856D01*
X370440Y-342871D01*
X370425Y-342888D01*
X370408Y-342903D01*
X370393Y-342920D01*
X370376Y-342935D01*
X370361Y-342952D01*
X370343Y-342968D01*
X370328Y-342985D01*
X370311Y-343000D01*
X370296Y-343017D01*
X370279Y-343032D01*
X370264Y-343049D01*
X370247Y-343064D01*
X370232Y-343082D01*
X370214Y-343097D01*
X370199Y-343114D01*
X370182Y-343129D01*
X370167Y-343146D01*
X370150Y-343161D01*
X370150Y-343161D01*
X370135Y-343178D01*
X370118Y-343193D01*
X370103Y-343211D01*
X370085Y-343226D01*
X370070Y-343243D01*
X370053Y-343258D01*
X370038Y-343275D01*
X370021Y-343290D01*
X370006Y-343307D01*
X369988Y-343322D01*
X369973Y-343340D01*
X369956Y-343355D01*
X369941Y-343372D01*
X369924Y-343387D01*
X369909Y-343404D01*
X369893Y-343418D01*
X369892Y-343419D01*
X369877Y-343436D01*
X369859Y-343451D01*
X369844Y-343469D01*
X369805Y-343503D01*
X369761Y-343532D01*
X369732Y-343547D01*
X369730Y-343548D01*
X369725Y-343554D01*
X369715Y-343566D01*
X369698Y-343581D01*
X369683Y-343598D01*
X369667Y-343612D01*
X369666Y-343613D01*
X369651Y-343630D01*
X369634Y-343645D01*
X369619Y-343662D01*
X369601Y-343677D01*
X369586Y-343694D01*
X369569Y-343710D01*
X369554Y-343727D01*
X369537Y-343742D01*
X369522Y-343759D01*
X369505Y-343774D01*
X369490Y-343791D01*
X369472Y-343806D01*
X369457Y-343824D01*
X369440Y-343839D01*
X369425Y-343856D01*
X369408Y-343871D01*
X369393Y-343888D01*
X369376Y-343903D01*
X369360Y-343920D01*
X369343Y-343935D01*
X369342Y-343937D01*
X369335Y-343951D01*
X369327Y-343966D01*
X369298Y-344010D01*
X369277Y-344034D01*
X369263Y-344063D01*
X369256Y-344073D01*
X369254Y-344081D01*
X369252Y-344084D01*
Y-344089D01*
Y-344121D01*
Y-344153D01*
Y-344185D01*
Y-344218D01*
Y-344250D01*
Y-344282D01*
Y-344314D01*
Y-344347D01*
Y-344379D01*
Y-344411D01*
Y-344443D01*
Y-344476D01*
Y-344508D01*
Y-344540D01*
Y-344572D01*
Y-344605D01*
Y-344637D01*
Y-344669D01*
Y-344702D01*
Y-344734D01*
Y-344766D01*
Y-344798D01*
Y-344831D01*
Y-344863D01*
D01*
Y-344895D01*
Y-344927D01*
Y-344960D01*
Y-344992D01*
Y-345024D01*
Y-345056D01*
Y-345089D01*
Y-345121D01*
Y-345153D01*
Y-345185D01*
Y-345195D01*
X369263Y-345211D01*
X369277Y-345240D01*
X369298Y-345264D01*
X369313Y-345286D01*
X369327Y-345274D01*
X369342Y-345257D01*
X369359Y-345242D01*
X369374Y-345225D01*
X369391Y-345210D01*
X369407Y-345192D01*
X369424Y-345177D01*
X369439Y-345160D01*
X369439Y-345160D01*
X369456Y-345145D01*
X369471Y-345128D01*
X369488Y-345113D01*
X369503Y-345096D01*
X369520Y-345080D01*
X369536Y-345063D01*
X369553Y-345048D01*
X369568Y-345031D01*
X369585Y-345016D01*
X369600Y-344999D01*
X369617Y-344984D01*
X369632Y-344967D01*
X369640Y-344960D01*
X369650Y-344952D01*
X369665Y-344934D01*
X369682Y-344919D01*
X369697Y-344902D01*
X369714Y-344887D01*
X369729Y-344870D01*
X369746Y-344855D01*
X369761Y-344837D01*
X369779Y-344822D01*
X369794Y-344805D01*
X369833Y-344771D01*
X369877Y-344742D01*
X369906Y-344727D01*
X369908Y-344726D01*
X369923Y-344708D01*
X369940Y-344693D01*
X369955Y-344676D01*
X369972Y-344661D01*
X369987Y-344644D01*
X369990Y-344642D01*
X370005Y-344629D01*
X370020Y-344612D01*
X370037Y-344597D01*
X370052Y-344579D01*
X370069Y-344564D01*
X370084Y-344547D01*
X370087Y-344545D01*
X370101Y-344532D01*
X370116Y-344515D01*
X370133Y-344500D01*
X370148Y-344483D01*
X370166Y-344467D01*
X370181Y-344450D01*
X370198Y-344435D01*
X370213Y-344418D01*
X370230Y-344403D01*
X370245Y-344386D01*
X370253Y-344379D01*
X370263Y-344371D01*
X370278Y-344354D01*
X370295Y-344338D01*
X370310Y-344321D01*
X370327Y-344306D01*
X370342Y-344289D01*
X370350Y-344282D01*
X370359Y-344274D01*
X370374Y-344257D01*
X370392Y-344242D01*
X370407Y-344225D01*
X370424Y-344210D01*
X370439Y-344192D01*
X370456Y-344177D01*
X370471Y-344160D01*
X370488Y-344145D01*
X370503Y-344128D01*
X370521Y-344113D01*
X370536Y-344095D01*
X370549Y-344084D01*
X370553Y-344080D01*
X370568Y-344063D01*
X370576Y-344056D01*
X370585Y-344048D01*
X370600Y-344031D01*
X370617Y-344016D01*
X370633Y-343999D01*
X370650Y-343984D01*
X370665Y-343966D01*
X370665Y-343966D01*
X370682Y-343951D01*
X370697Y-343934D01*
X370714Y-343919D01*
X370729Y-343902D01*
X370746Y-343887D01*
X370761Y-343870D01*
X370779Y-343855D01*
X370794Y-343837D01*
X370811Y-343822D01*
X370826Y-343805D01*
X370843Y-343790D01*
X370858Y-343773D01*
X370874Y-343759D01*
X370876Y-343758D01*
X370891Y-343741D01*
X370908Y-343725D01*
X370923Y-343708D01*
X370940Y-343693D01*
X370955Y-343676D01*
X370971Y-343662D01*
X370972Y-343661D01*
X370987Y-343644D01*
X371003Y-343630D01*
X371005Y-343629D01*
X371020Y-343612D01*
X371037Y-343596D01*
X371052Y-343579D01*
X371069Y-343564D01*
X371084Y-343547D01*
X371101Y-343532D01*
X371116Y-343515D01*
X371129Y-343503D01*
X371134Y-343500D01*
X371149Y-343482D01*
X371166Y-343467D01*
X371181Y-343450D01*
X371181Y-343450D01*
X371198Y-343435D01*
X371212Y-343419D01*
X371213Y-343418D01*
X371229Y-343404D01*
X371230Y-343403D01*
X371245Y-343386D01*
X371263Y-343371D01*
X371278Y-343354D01*
X371295Y-343338D01*
X371310Y-343321D01*
X371318Y-343314D01*
X371327Y-343306D01*
X371342Y-343289D01*
X371350Y-343282D01*
X371359Y-343274D01*
X371375Y-343257D01*
X371392Y-343242D01*
X371407Y-343224D01*
X371407Y-343224D01*
X371424Y-343209D01*
X371439Y-343192D01*
X371456Y-343177D01*
X371471Y-343160D01*
X371488Y-343145D01*
X371503Y-343128D01*
X371505Y-343126D01*
X371521Y-343113D01*
X371536Y-343095D01*
X371553Y-343080D01*
X371568Y-343063D01*
X371585Y-343048D01*
X371600Y-343031D01*
X371608Y-343024D01*
X371618Y-343016D01*
X371633Y-342999D01*
X371650Y-342984D01*
X371665Y-342966D01*
X371682Y-342951D01*
X371697Y-342934D01*
X371714Y-342919D01*
X371729Y-342902D01*
X371747Y-342887D01*
X371762Y-342869D01*
X371779Y-342854D01*
X371794Y-342837D01*
X371811Y-342822D01*
X371826Y-342805D01*
X371843Y-342790D01*
X371858Y-342773D01*
X371876Y-342758D01*
X371891Y-342741D01*
X371899Y-342734D01*
X371908Y-342725D01*
X371923Y-342708D01*
X371926Y-342706D01*
X371940Y-342693D01*
X371955Y-342676D01*
X371963Y-342669D01*
X371972Y-342661D01*
X371988Y-342644D01*
X372005Y-342629D01*
X372020Y-342611D01*
X372037Y-342596D01*
X372052Y-342579D01*
X372055Y-342577D01*
X372069Y-342564D01*
X372084Y-342547D01*
X372101Y-342532D01*
X372116Y-342515D01*
X372134Y-342500D01*
X372149Y-342482D01*
X372166Y-342467D01*
X372181Y-342450D01*
X372198Y-342435D01*
X372213Y-342418D01*
X372213Y-342418D01*
X372231Y-342403D01*
X372246Y-342386D01*
X372263Y-342371D01*
X372278Y-342353D01*
X372295Y-342338D01*
X372310Y-342321D01*
X372318Y-342314D01*
X372327Y-342306D01*
X372342Y-342289D01*
X372350Y-342282D01*
X372359Y-342274D01*
X372375Y-342257D01*
X372392Y-342242D01*
X372407Y-342224D01*
X372424Y-342209D01*
X372439Y-342192D01*
X372456Y-342177D01*
X372471Y-342160D01*
X372479Y-342153D01*
X372489Y-342145D01*
X372504Y-342127D01*
X372521Y-342112D01*
X372536Y-342095D01*
X372575Y-342061D01*
X372619Y-342032D01*
X372648Y-342017D01*
X372650Y-342016D01*
X372665Y-341999D01*
X372682Y-341983D01*
X372697Y-341966D01*
X372705Y-341959D01*
X372714Y-341951D01*
X372714Y-341951D01*
X372729Y-341934D01*
X372747Y-341919D01*
X372762Y-341902D01*
X372779Y-341887D01*
X372794Y-341869D01*
X372811Y-341854D01*
X372826Y-341837D01*
X372843Y-341822D01*
X372859Y-341805D01*
X372866Y-341798D01*
X372876Y-341790D01*
X372891Y-341773D01*
X372908Y-341758D01*
X372923Y-341740D01*
X372940Y-341725D01*
X372955Y-341708D01*
X372972Y-341693D01*
X372988Y-341676D01*
X373001Y-341664D01*
X373005Y-341661D01*
X373020Y-341644D01*
X373037Y-341629D01*
X373052Y-341611D01*
X373055Y-341609D01*
X373069Y-341596D01*
X373084Y-341579D01*
X373102Y-341564D01*
X373117Y-341547D01*
X373134Y-341532D01*
X373149Y-341514D01*
X373157Y-341508D01*
X373166Y-341499D01*
X373181Y-341482D01*
X373189Y-341475D01*
X373198Y-341467D01*
X373213Y-341450D01*
X373231Y-341435D01*
X373246Y-341418D01*
X373263Y-341403D01*
X373278Y-341386D01*
X373295Y-341370D01*
X373310Y-341353D01*
X373327Y-341338D01*
X373342Y-341321D01*
X373360Y-341306D01*
X373375Y-341289D01*
X373392Y-341274D01*
X373407Y-341256D01*
X373424Y-341241D01*
X373439Y-341224D01*
X373456Y-341209D01*
X373471Y-341192D01*
X373489Y-341177D01*
X373490Y-341175D01*
X373505Y-341146D01*
X373534Y-341102D01*
X373555Y-341078D01*
X373569Y-341049D01*
X373575Y-341040D01*
X373578Y-341032D01*
X373601Y-340985D01*
X373608Y-340975D01*
X373610Y-340967D01*
X373614Y-340959D01*
X373616Y-340939D01*
X373626Y-340888D01*
X373643Y-340838D01*
X373644Y-340834D01*
Y-340830D01*
Y-340798D01*
Y-340766D01*
Y-340733D01*
Y-340701D01*
Y-340669D01*
Y-340637D01*
Y-340604D01*
Y-340572D01*
Y-340540D01*
Y-340508D01*
Y-340475D01*
Y-340443D01*
Y-340411D01*
Y-340378D01*
Y-340346D01*
Y-340314D01*
Y-340282D01*
Y-340249D01*
Y-340217D01*
Y-340185D01*
Y-340153D01*
Y-340120D01*
Y-340088D01*
Y-340056D01*
Y-340024D01*
Y-339991D01*
Y-339959D01*
Y-339927D01*
Y-339895D01*
Y-339862D01*
Y-339830D01*
Y-339798D01*
Y-339766D01*
Y-339733D01*
Y-339701D01*
Y-339669D01*
Y-339636D01*
Y-339604D01*
Y-339572D01*
Y-339540D01*
Y-339507D01*
Y-339475D01*
Y-339443D01*
Y-339411D01*
Y-339378D01*
Y-339346D01*
D01*
Y-339314D01*
Y-339282D01*
Y-339249D01*
Y-339217D01*
Y-339185D01*
Y-339153D01*
Y-339120D01*
Y-339088D01*
Y-339056D01*
Y-339023D01*
Y-338991D01*
Y-338959D01*
Y-338927D01*
Y-338894D01*
Y-338862D01*
Y-338830D01*
Y-338798D01*
Y-338765D01*
Y-338733D01*
Y-338701D01*
Y-338669D01*
Y-338636D01*
Y-338604D01*
Y-338572D01*
Y-338540D01*
Y-338507D01*
Y-338475D01*
Y-338443D01*
Y-338410D01*
Y-338378D01*
Y-338346D01*
Y-338314D01*
Y-338281D01*
Y-338249D01*
Y-338217D01*
Y-338185D01*
Y-338152D01*
Y-338120D01*
Y-338088D01*
Y-338056D01*
Y-338023D01*
Y-337991D01*
Y-337959D01*
Y-337927D01*
Y-337894D01*
Y-337862D01*
Y-337830D01*
Y-337797D01*
Y-337765D01*
Y-337733D01*
Y-337701D01*
Y-337668D01*
Y-337636D01*
Y-337604D01*
Y-337572D01*
Y-337539D01*
Y-337507D01*
Y-337475D01*
Y-337443D01*
Y-337410D01*
Y-337378D01*
Y-337346D01*
Y-337314D01*
Y-337281D01*
Y-337249D01*
Y-337217D01*
Y-337185D01*
Y-337152D01*
Y-337120D01*
Y-337088D01*
Y-337055D01*
Y-337023D01*
Y-336991D01*
Y-336959D01*
Y-336927D01*
Y-336894D01*
Y-336862D01*
Y-336830D01*
Y-336797D01*
Y-336765D01*
Y-336733D01*
Y-336701D01*
Y-336668D01*
Y-336636D01*
Y-336604D01*
Y-336572D01*
Y-336539D01*
Y-336507D01*
Y-336475D01*
Y-336442D01*
Y-336410D01*
Y-336378D01*
Y-336346D01*
Y-336314D01*
Y-336281D01*
Y-336249D01*
Y-336217D01*
Y-336184D01*
Y-336152D01*
Y-336120D01*
Y-336088D01*
D01*
Y-336055D01*
Y-336023D01*
Y-335991D01*
Y-335959D01*
Y-335926D01*
Y-335894D01*
Y-335862D01*
Y-335830D01*
Y-335797D01*
Y-335765D01*
Y-335733D01*
Y-335700D01*
Y-335668D01*
Y-335636D01*
Y-335604D01*
Y-335572D01*
Y-335539D01*
Y-335507D01*
Y-335475D01*
Y-335442D01*
Y-335410D01*
Y-335378D01*
Y-335346D01*
Y-335313D01*
Y-335281D01*
Y-335249D01*
Y-335217D01*
Y-335184D01*
Y-335152D01*
Y-335120D01*
Y-335087D01*
Y-335055D01*
Y-335023D01*
Y-334991D01*
Y-334959D01*
Y-334926D01*
Y-334894D01*
Y-334862D01*
Y-334829D01*
Y-334797D01*
Y-334765D01*
Y-334733D01*
Y-334700D01*
Y-334668D01*
Y-334636D01*
Y-334604D01*
Y-334571D01*
Y-334539D01*
Y-334507D01*
Y-334474D01*
Y-334442D01*
Y-334410D01*
Y-334378D01*
Y-334346D01*
Y-334313D01*
Y-334281D01*
Y-334249D01*
Y-334216D01*
Y-334184D01*
Y-334152D01*
Y-334120D01*
Y-334087D01*
Y-334055D01*
Y-334023D01*
Y-333991D01*
Y-333958D01*
Y-333926D01*
Y-333894D01*
Y-333862D01*
Y-333829D01*
Y-333797D01*
Y-333765D01*
Y-333733D01*
Y-333700D01*
Y-333668D01*
Y-333636D01*
Y-333604D01*
Y-333571D01*
Y-333539D01*
Y-333507D01*
Y-333474D01*
Y-333442D01*
Y-333410D01*
Y-333378D01*
Y-333345D01*
Y-333313D01*
Y-333281D01*
Y-333249D01*
Y-333216D01*
Y-333184D01*
Y-333152D01*
Y-333120D01*
Y-333087D01*
Y-333055D01*
Y-333023D01*
Y-332991D01*
Y-332958D01*
Y-332926D01*
Y-332894D01*
Y-332861D01*
Y-332829D01*
Y-332797D01*
Y-332765D01*
Y-332732D01*
Y-332700D01*
Y-332668D01*
Y-332636D01*
Y-332603D01*
Y-332571D01*
Y-332539D01*
Y-332507D01*
Y-332474D01*
Y-332442D01*
Y-332410D01*
Y-332378D01*
Y-332345D01*
Y-332313D01*
Y-332281D01*
Y-332248D01*
Y-332216D01*
Y-332184D01*
Y-332152D01*
Y-332119D01*
Y-332087D01*
Y-332055D01*
Y-332023D01*
Y-331990D01*
Y-331958D01*
Y-331926D01*
Y-331894D01*
Y-331861D01*
Y-331829D01*
Y-331797D01*
Y-331765D01*
Y-331732D01*
Y-331700D01*
Y-331668D01*
Y-331635D01*
Y-331603D01*
Y-331571D01*
Y-331539D01*
Y-331506D01*
Y-331474D01*
Y-331442D01*
Y-331410D01*
Y-331377D01*
Y-331345D01*
Y-331313D01*
Y-331281D01*
Y-331248D01*
Y-331216D01*
Y-331184D01*
Y-331152D01*
Y-331119D01*
Y-331115D01*
X373643Y-331111D01*
X373626Y-331062D01*
X373616Y-331010D01*
X373615Y-330996D01*
X373601Y-330983D01*
X373585Y-330966D01*
X373568Y-330951D01*
X373560Y-330941D01*
X373553Y-330934D01*
X373536Y-330919D01*
X373521Y-330902D01*
X373504Y-330887D01*
X373495Y-330877D01*
X373489Y-330869D01*
X373471Y-330854D01*
X373463Y-330845D01*
X373456Y-330837D01*
X373439Y-330822D01*
X373424Y-330805D01*
X373407Y-330790D01*
X373392Y-330773D01*
X373375Y-330757D01*
X373360Y-330740D01*
X373342Y-330725D01*
X373327Y-330708D01*
X373310Y-330693D01*
X373295Y-330676D01*
X373278Y-330661D01*
X373263Y-330644D01*
X373246Y-330628D01*
X373231Y-330611D01*
X373213Y-330596D01*
X373198Y-330579D01*
X373181Y-330564D01*
X373166Y-330547D01*
X373149Y-330532D01*
X373134Y-330515D01*
X373117Y-330500D01*
X373102Y-330482D01*
X373084Y-330467D01*
X373069Y-330450D01*
X373052Y-330435D01*
X373037Y-330418D01*
X373020Y-330403D01*
X373005Y-330385D01*
X372988Y-330370D01*
X372972Y-330353D01*
X372955Y-330338D01*
X372949Y-330331D01*
X372940Y-330321D01*
X372923Y-330306D01*
X372908Y-330289D01*
X372891Y-330274D01*
X372876Y-330256D01*
X372859Y-330241D01*
X372846Y-330227D01*
X372832Y-330226D01*
X372780Y-330216D01*
X372730Y-330199D01*
X372727Y-330198D01*
D02*
G37*
G36*
X356191Y-345653D02*
X356190Y-345654D01*
X356188Y-345661D01*
X356165Y-345708D01*
X356135Y-345752D01*
X356101Y-345792D01*
X356084Y-345807D01*
X356082Y-345808D01*
X356068Y-345838D01*
X356039Y-345881D01*
X356004Y-345921D01*
X355987Y-345936D01*
X355972Y-345953D01*
X355955Y-345968D01*
X355940Y-345985D01*
X355900Y-346020D01*
X355856Y-346049D01*
X355827Y-346063D01*
X355825Y-346065D01*
X355810Y-346082D01*
X355793Y-346097D01*
X355778Y-346114D01*
X355739Y-346149D01*
X355695Y-346178D01*
X355648Y-346201D01*
X355640Y-346204D01*
X355640Y-346204D01*
X356191D01*
Y-346186D01*
Y-346153D01*
Y-346121D01*
Y-346089D01*
Y-346057D01*
Y-346024D01*
Y-345992D01*
Y-345960D01*
Y-345928D01*
Y-345895D01*
Y-345863D01*
Y-345831D01*
Y-345798D01*
Y-345766D01*
Y-345734D01*
Y-345702D01*
Y-345669D01*
Y-345653D01*
D02*
G37*
G36*
X388342Y-341650D02*
X384286D01*
Y-341669D01*
Y-341701D01*
Y-341734D01*
Y-341766D01*
Y-341798D01*
Y-341830D01*
Y-341863D01*
Y-341895D01*
Y-341927D01*
Y-341959D01*
Y-341992D01*
Y-342024D01*
Y-342056D01*
Y-342088D01*
Y-342121D01*
Y-342153D01*
Y-342185D01*
Y-342217D01*
Y-342250D01*
Y-342282D01*
Y-342314D01*
Y-342346D01*
Y-342379D01*
Y-342411D01*
Y-342443D01*
Y-342476D01*
Y-342508D01*
Y-342540D01*
Y-342572D01*
Y-342604D01*
Y-342637D01*
Y-342669D01*
Y-342701D01*
Y-342734D01*
Y-342766D01*
Y-342798D01*
Y-342830D01*
Y-342863D01*
Y-342895D01*
Y-342927D01*
Y-342959D01*
Y-342992D01*
Y-343024D01*
Y-343056D01*
Y-343089D01*
Y-343121D01*
Y-343153D01*
Y-343185D01*
Y-343217D01*
Y-343250D01*
Y-343282D01*
Y-343314D01*
Y-343347D01*
Y-343379D01*
Y-343411D01*
Y-343443D01*
Y-343476D01*
Y-343508D01*
Y-343540D01*
Y-343572D01*
Y-343605D01*
Y-343637D01*
Y-343669D01*
Y-343701D01*
Y-343734D01*
Y-343766D01*
Y-343798D01*
Y-343830D01*
Y-343863D01*
Y-343895D01*
Y-343927D01*
Y-343959D01*
Y-343992D01*
Y-344024D01*
Y-344056D01*
Y-344089D01*
Y-344121D01*
Y-344153D01*
Y-344185D01*
Y-344218D01*
Y-344250D01*
Y-344282D01*
Y-344314D01*
Y-344347D01*
Y-344379D01*
Y-344411D01*
Y-344443D01*
Y-344476D01*
Y-344508D01*
Y-344540D01*
Y-344572D01*
Y-344605D01*
Y-344637D01*
Y-344669D01*
Y-344702D01*
Y-344734D01*
Y-344766D01*
Y-344798D01*
Y-344831D01*
Y-344863D01*
Y-344895D01*
Y-344927D01*
Y-344960D01*
Y-344992D01*
D01*
Y-345024D01*
Y-345056D01*
Y-345089D01*
Y-345121D01*
Y-345153D01*
Y-345185D01*
Y-345218D01*
Y-345250D01*
Y-345282D01*
Y-345315D01*
Y-345347D01*
Y-345379D01*
Y-345411D01*
Y-345444D01*
Y-345476D01*
Y-345508D01*
Y-345540D01*
Y-345573D01*
Y-345605D01*
Y-345637D01*
Y-345669D01*
Y-345702D01*
Y-345734D01*
Y-345766D01*
Y-345798D01*
Y-345831D01*
Y-345863D01*
Y-345895D01*
Y-345928D01*
Y-345960D01*
Y-345992D01*
Y-346024D01*
Y-346057D01*
Y-346089D01*
Y-346121D01*
Y-346153D01*
Y-346186D01*
Y-346218D01*
Y-346250D01*
Y-346282D01*
Y-346315D01*
Y-346347D01*
Y-346379D01*
Y-346411D01*
Y-346444D01*
Y-346476D01*
Y-346508D01*
Y-346540D01*
Y-346573D01*
Y-346605D01*
Y-346637D01*
Y-346670D01*
Y-346702D01*
Y-346734D01*
Y-346766D01*
Y-346799D01*
Y-346831D01*
Y-346863D01*
Y-346895D01*
Y-346928D01*
Y-346960D01*
Y-346992D01*
Y-347024D01*
Y-347057D01*
Y-347089D01*
Y-347121D01*
Y-347153D01*
Y-347186D01*
Y-347218D01*
Y-347250D01*
Y-347283D01*
Y-347315D01*
Y-347347D01*
Y-347379D01*
Y-347411D01*
Y-347444D01*
Y-347476D01*
Y-347508D01*
Y-347541D01*
Y-347573D01*
Y-347605D01*
Y-347637D01*
Y-347670D01*
Y-347702D01*
Y-347734D01*
Y-347766D01*
Y-347799D01*
Y-347831D01*
Y-347863D01*
Y-347882D01*
X388438D01*
X388442Y-347880D01*
X388492Y-347863D01*
X388543Y-347853D01*
X388558Y-347852D01*
X388570Y-347838D01*
X388587Y-347823D01*
X388602Y-347806D01*
X388619Y-347791D01*
X388634Y-347773D01*
X388652Y-347758D01*
X388667Y-347741D01*
X388684Y-347726D01*
X388699Y-347709D01*
X388702Y-347707D01*
X388716Y-347694D01*
X388731Y-347676D01*
X388739Y-347670D01*
X388749Y-347661D01*
X388764Y-347644D01*
X388772Y-347637D01*
X388781Y-347629D01*
X388796Y-347612D01*
X388813Y-347597D01*
X388828Y-347580D01*
X388836Y-347573D01*
X388845Y-347565D01*
X388860Y-347548D01*
X388868Y-347541D01*
X388878Y-347532D01*
X388893Y-347515D01*
X388910Y-347500D01*
X388925Y-347483D01*
X388938Y-347471D01*
X388942Y-347468D01*
X388957Y-347451D01*
X388974Y-347436D01*
X388989Y-347418D01*
X389007Y-347403D01*
X389022Y-347386D01*
X389024Y-347384D01*
X389039Y-347371D01*
X389054Y-347354D01*
X389071Y-347339D01*
X389086Y-347322D01*
X389103Y-347307D01*
X389119Y-347289D01*
X389136Y-347274D01*
X389151Y-347257D01*
X389168Y-347242D01*
X389183Y-347225D01*
X389200Y-347210D01*
X389215Y-347193D01*
X389232Y-347178D01*
X389247Y-347160D01*
X389263Y-347147D01*
X389265Y-347145D01*
X389280Y-347128D01*
X389297Y-347113D01*
X389312Y-347096D01*
X389329Y-347081D01*
X389343Y-347065D01*
X389354Y-347032D01*
X389358Y-347024D01*
X389358Y-347024D01*
X389359Y-347004D01*
X389370Y-346953D01*
X389387Y-346903D01*
X389388Y-346900D01*
Y-346895D01*
Y-346863D01*
Y-346831D01*
Y-346799D01*
Y-346766D01*
Y-346734D01*
Y-346702D01*
Y-346670D01*
Y-346637D01*
Y-346605D01*
Y-346573D01*
Y-346540D01*
Y-346508D01*
Y-346476D01*
Y-346444D01*
Y-346411D01*
Y-346379D01*
Y-346347D01*
Y-346315D01*
Y-346282D01*
Y-346250D01*
Y-346218D01*
Y-346186D01*
Y-346153D01*
Y-346121D01*
Y-346089D01*
Y-346057D01*
Y-346024D01*
Y-345992D01*
Y-345960D01*
Y-345928D01*
Y-345895D01*
Y-345863D01*
Y-345831D01*
Y-345798D01*
Y-345766D01*
Y-345734D01*
Y-345702D01*
Y-345669D01*
Y-345637D01*
Y-345605D01*
Y-345573D01*
Y-345540D01*
Y-345508D01*
Y-345476D01*
Y-345444D01*
Y-345411D01*
Y-345379D01*
Y-345347D01*
Y-345315D01*
Y-345282D01*
Y-345250D01*
Y-345218D01*
Y-345185D01*
Y-345153D01*
Y-345121D01*
Y-345089D01*
Y-345056D01*
Y-345024D01*
Y-344992D01*
D01*
Y-344960D01*
Y-344927D01*
Y-344895D01*
Y-344863D01*
D01*
Y-344831D01*
Y-344798D01*
Y-344766D01*
Y-344734D01*
Y-344702D01*
Y-344669D01*
Y-344637D01*
Y-344605D01*
Y-344572D01*
Y-344540D01*
Y-344508D01*
Y-344476D01*
Y-344443D01*
Y-344411D01*
Y-344379D01*
Y-344347D01*
Y-344314D01*
Y-344282D01*
Y-344250D01*
Y-344218D01*
Y-344185D01*
Y-344153D01*
Y-344121D01*
Y-344089D01*
Y-344056D01*
Y-344024D01*
Y-343992D01*
Y-343959D01*
Y-343927D01*
Y-343895D01*
Y-343863D01*
Y-343830D01*
Y-343798D01*
Y-343766D01*
Y-343734D01*
Y-343701D01*
Y-343669D01*
Y-343637D01*
Y-343605D01*
Y-343572D01*
Y-343540D01*
Y-343508D01*
Y-343476D01*
Y-343443D01*
Y-343411D01*
Y-343379D01*
Y-343347D01*
Y-343314D01*
Y-343282D01*
Y-343250D01*
Y-343217D01*
Y-343185D01*
Y-343153D01*
Y-343121D01*
Y-343089D01*
Y-343056D01*
Y-343024D01*
Y-342992D01*
Y-342959D01*
Y-342927D01*
Y-342895D01*
Y-342863D01*
Y-342830D01*
Y-342798D01*
Y-342766D01*
Y-342734D01*
Y-342701D01*
Y-342669D01*
Y-342637D01*
Y-342632D01*
X389387Y-342629D01*
X389370Y-342579D01*
X389359Y-342528D01*
X389358Y-342513D01*
X389344Y-342501D01*
X389329Y-342484D01*
X389312Y-342469D01*
X389297Y-342451D01*
X389280Y-342436D01*
X389270Y-342425D01*
X389265Y-342419D01*
X389247Y-342404D01*
X389232Y-342387D01*
X389232Y-342387D01*
X389215Y-342372D01*
X389200Y-342355D01*
X389183Y-342339D01*
X389168Y-342322D01*
X389151Y-342307D01*
X389139Y-342294D01*
X389136Y-342290D01*
X389119Y-342275D01*
X389107Y-342262D01*
X389103Y-342258D01*
X389086Y-342243D01*
X389071Y-342226D01*
X389054Y-342211D01*
X389039Y-342193D01*
X389022Y-342178D01*
X389007Y-342161D01*
X388989Y-342146D01*
X388974Y-342129D01*
X388957Y-342114D01*
X388942Y-342096D01*
X388925Y-342081D01*
X388910Y-342064D01*
X388893Y-342049D01*
X388892Y-342048D01*
X388878Y-342032D01*
X388860Y-342017D01*
X388850Y-342005D01*
X388845Y-342000D01*
X388828Y-341985D01*
X388813Y-341967D01*
X388796Y-341952D01*
X388784Y-341939D01*
X388781Y-341935D01*
X388764Y-341920D01*
X388749Y-341903D01*
X388731Y-341888D01*
X388721Y-341877D01*
X388716Y-341871D01*
X388699Y-341856D01*
X388684Y-341838D01*
X388667Y-341823D01*
X388652Y-341806D01*
X388634Y-341791D01*
X388619Y-341774D01*
X388602Y-341759D01*
X388589Y-341744D01*
X388587Y-341742D01*
X388570Y-341727D01*
X388555Y-341709D01*
X388539Y-341695D01*
X388507Y-341684D01*
X388503Y-341683D01*
X388499D01*
X388446Y-341679D01*
X388395Y-341669D01*
X388345Y-341652D01*
X388342Y-341650D01*
D02*
G37*
G36*
X381470D02*
X377414D01*
Y-341669D01*
Y-341701D01*
Y-341734D01*
Y-341766D01*
Y-341798D01*
Y-341830D01*
Y-341863D01*
Y-341895D01*
Y-341927D01*
Y-341959D01*
Y-341992D01*
Y-342024D01*
Y-342056D01*
Y-342088D01*
Y-342121D01*
Y-342153D01*
Y-342185D01*
Y-342217D01*
Y-342250D01*
Y-342282D01*
Y-342314D01*
Y-342346D01*
Y-342379D01*
Y-342411D01*
Y-342443D01*
Y-342476D01*
Y-342508D01*
Y-342540D01*
Y-342572D01*
Y-342604D01*
Y-342637D01*
Y-342669D01*
Y-342701D01*
Y-342734D01*
Y-342766D01*
Y-342798D01*
Y-342830D01*
Y-342863D01*
Y-342895D01*
Y-342927D01*
Y-342959D01*
Y-342992D01*
Y-343024D01*
Y-343056D01*
Y-343089D01*
Y-343121D01*
Y-343153D01*
Y-343185D01*
Y-343217D01*
Y-343250D01*
Y-343282D01*
Y-343314D01*
Y-343347D01*
Y-343379D01*
Y-343411D01*
Y-343443D01*
Y-343476D01*
Y-343508D01*
Y-343540D01*
Y-343572D01*
Y-343605D01*
Y-343637D01*
Y-343669D01*
Y-343701D01*
Y-343734D01*
Y-343766D01*
Y-343798D01*
Y-343830D01*
Y-343863D01*
Y-343895D01*
Y-343927D01*
Y-343959D01*
Y-343992D01*
Y-344024D01*
Y-344056D01*
Y-344089D01*
Y-344121D01*
Y-344153D01*
Y-344185D01*
Y-344218D01*
Y-344250D01*
Y-344282D01*
Y-344314D01*
Y-344347D01*
Y-344379D01*
Y-344411D01*
Y-344443D01*
Y-344476D01*
Y-344508D01*
Y-344540D01*
Y-344572D01*
Y-344605D01*
Y-344637D01*
Y-344669D01*
Y-344702D01*
Y-344734D01*
Y-344766D01*
Y-344798D01*
Y-344831D01*
Y-344863D01*
Y-344895D01*
Y-344927D01*
Y-344960D01*
Y-344992D01*
D01*
Y-345024D01*
Y-345056D01*
Y-345089D01*
Y-345121D01*
Y-345153D01*
Y-345185D01*
Y-345218D01*
Y-345250D01*
Y-345282D01*
Y-345315D01*
Y-345347D01*
Y-345379D01*
Y-345411D01*
Y-345444D01*
Y-345476D01*
Y-345508D01*
Y-345540D01*
Y-345573D01*
Y-345605D01*
Y-345637D01*
Y-345669D01*
Y-345702D01*
Y-345734D01*
Y-345766D01*
Y-345798D01*
Y-345831D01*
Y-345863D01*
Y-345895D01*
Y-345928D01*
Y-345960D01*
Y-345992D01*
Y-346024D01*
Y-346057D01*
Y-346089D01*
Y-346121D01*
Y-346153D01*
Y-346186D01*
Y-346218D01*
Y-346250D01*
Y-346282D01*
Y-346315D01*
Y-346347D01*
Y-346379D01*
Y-346411D01*
Y-346444D01*
Y-346476D01*
Y-346508D01*
Y-346540D01*
Y-346573D01*
Y-346605D01*
Y-346637D01*
Y-346670D01*
Y-346702D01*
Y-346734D01*
Y-346766D01*
Y-346799D01*
Y-346831D01*
Y-346863D01*
Y-346895D01*
Y-346928D01*
Y-346960D01*
Y-346992D01*
Y-347024D01*
Y-347057D01*
Y-347089D01*
Y-347121D01*
Y-347153D01*
Y-347186D01*
Y-347218D01*
Y-347250D01*
Y-347283D01*
Y-347315D01*
Y-347347D01*
Y-347379D01*
Y-347411D01*
Y-347444D01*
Y-347476D01*
Y-347508D01*
Y-347541D01*
Y-347573D01*
Y-347605D01*
Y-347637D01*
Y-347670D01*
Y-347702D01*
Y-347734D01*
Y-347766D01*
Y-347799D01*
Y-347831D01*
Y-347863D01*
Y-347882D01*
X378419D01*
Y-347863D01*
Y-347831D01*
Y-347799D01*
Y-347766D01*
Y-347734D01*
Y-347702D01*
Y-347670D01*
Y-347637D01*
Y-347605D01*
Y-347573D01*
Y-347541D01*
Y-347508D01*
Y-347476D01*
Y-347444D01*
Y-347411D01*
Y-347379D01*
Y-347347D01*
Y-347315D01*
Y-347283D01*
Y-347250D01*
Y-347218D01*
Y-347186D01*
Y-347153D01*
Y-347121D01*
Y-347089D01*
Y-347057D01*
Y-347024D01*
Y-346992D01*
Y-346960D01*
Y-346928D01*
Y-346895D01*
Y-346863D01*
Y-346831D01*
Y-346799D01*
Y-346766D01*
Y-346734D01*
Y-346702D01*
Y-346670D01*
Y-346637D01*
Y-346605D01*
Y-346573D01*
Y-346540D01*
Y-346536D01*
X378417Y-346533D01*
X378401Y-346483D01*
X378390Y-346431D01*
X378387Y-346379D01*
Y-346347D01*
X378390Y-346295D01*
X378401Y-346243D01*
X378417Y-346194D01*
X378419Y-346190D01*
Y-346186D01*
X378423Y-346133D01*
X378433Y-346082D01*
X378450Y-346032D01*
X378473Y-345985D01*
X378502Y-345942D01*
X378537Y-345902D01*
X378576Y-345868D01*
X378620Y-345838D01*
X378667Y-345815D01*
X378716Y-345798D01*
X378768Y-345788D01*
X378820Y-345785D01*
X380046D01*
X380098Y-345788D01*
X380150Y-345798D01*
X380199Y-345815D01*
X380246Y-345838D01*
X380290Y-345868D01*
X380329Y-345902D01*
X380364Y-345942D01*
X380393Y-345985D01*
X380416Y-346032D01*
X380419Y-346040D01*
X380425Y-346050D01*
X380440Y-346079D01*
X380461Y-346103D01*
X380490Y-346146D01*
X380513Y-346194D01*
X380516Y-346201D01*
X380522Y-346211D01*
X380537Y-346240D01*
X380558Y-346264D01*
X380587Y-346308D01*
X380610Y-346355D01*
X380613Y-346363D01*
X380619Y-346372D01*
X380642Y-346419D01*
X380645Y-346427D01*
X380651Y-346437D01*
X380666Y-346466D01*
X380687Y-346490D01*
X380716Y-346534D01*
X380739Y-346581D01*
X380742Y-346589D01*
X380748Y-346598D01*
X380763Y-346627D01*
X380783Y-346651D01*
X380813Y-346695D01*
X380836Y-346742D01*
X380838Y-346750D01*
X380845Y-346759D01*
X380859Y-346789D01*
X380880Y-346813D01*
X380909Y-346856D01*
X380932Y-346903D01*
X380935Y-346911D01*
X380935Y-346911D01*
X380942Y-346921D01*
X380965Y-346968D01*
X380967Y-346976D01*
X380974Y-346985D01*
X380985Y-347008D01*
X380988Y-347015D01*
X381009Y-347039D01*
X381038Y-347082D01*
X381062Y-347129D01*
X381064Y-347137D01*
X381071Y-347147D01*
X381085Y-347176D01*
X381106Y-347200D01*
X381135Y-347243D01*
X381158Y-347290D01*
X381161Y-347298D01*
X381167Y-347308D01*
X381182Y-347337D01*
X381187Y-347342D01*
X381203Y-347361D01*
X381232Y-347405D01*
X381255Y-347452D01*
X381258Y-347460D01*
X381264Y-347469D01*
X381279Y-347498D01*
X381300Y-347522D01*
X381329Y-347566D01*
X381352Y-347613D01*
X381355Y-347621D01*
X381361Y-347631D01*
X381384Y-347677D01*
X381387Y-347686D01*
X381393Y-347695D01*
X381408Y-347724D01*
X381429Y-347748D01*
X381458Y-347792D01*
X381481Y-347839D01*
X381484Y-347847D01*
X381490Y-347856D01*
X381503Y-347882D01*
X382528D01*
X382523Y-347873D01*
X382503Y-347849D01*
X382473Y-347806D01*
X382450Y-347759D01*
X382447Y-347750D01*
X382441Y-347741D01*
X382427Y-347712D01*
X382406Y-347688D01*
X382377Y-347644D01*
X382353Y-347597D01*
X382351Y-347589D01*
X382344Y-347580D01*
X382337Y-347566D01*
X382330Y-347550D01*
X382328Y-347548D01*
X382309Y-347527D01*
X382280Y-347483D01*
X382257Y-347436D01*
X382257Y-347436D01*
X382254Y-347428D01*
X382247Y-347418D01*
X382233Y-347389D01*
X382212Y-347365D01*
X382183Y-347322D01*
X382160Y-347275D01*
X382157Y-347267D01*
X382156Y-347266D01*
X382151Y-347257D01*
X382143Y-347242D01*
X382136Y-347228D01*
X382115Y-347204D01*
X382086Y-347160D01*
X382063Y-347113D01*
X382060Y-347105D01*
X382054Y-347096D01*
X382039Y-347066D01*
X382019Y-347043D01*
X381989Y-346999D01*
X381966Y-346952D01*
X381963Y-346944D01*
X381957Y-346935D01*
X381948Y-346915D01*
X381943Y-346905D01*
X381922Y-346881D01*
X381893Y-346838D01*
X381870Y-346791D01*
X381867Y-346783D01*
X381860Y-346773D01*
X381857Y-346766D01*
X381846Y-346744D01*
X381825Y-346720D01*
X381796Y-346676D01*
X381773Y-346629D01*
X381770Y-346621D01*
X381764Y-346612D01*
X381740Y-346565D01*
X381738Y-346557D01*
X381731Y-346547D01*
X381717Y-346518D01*
X381696Y-346494D01*
X381667Y-346451D01*
X381644Y-346404D01*
X381641Y-346395D01*
X381635Y-346386D01*
X381624Y-346364D01*
X381620Y-346357D01*
X381599Y-346333D01*
X381570Y-346289D01*
X381547Y-346242D01*
X381530Y-346193D01*
X381520Y-346141D01*
X381516Y-346089D01*
Y-346057D01*
Y-346024D01*
X381520Y-345972D01*
X381530Y-345920D01*
X381547Y-345871D01*
X381570Y-345824D01*
X381599Y-345780D01*
X381634Y-345741D01*
X381651Y-345726D01*
X381666Y-345709D01*
X381682Y-345695D01*
X381683Y-345693D01*
X381698Y-345676D01*
X381714Y-345662D01*
X381715Y-345661D01*
X381731Y-345644D01*
X381748Y-345629D01*
X381763Y-345612D01*
X381780Y-345597D01*
X381795Y-345580D01*
X381795Y-345580D01*
X381812Y-345564D01*
X381827Y-345547D01*
X381844Y-345532D01*
X381860Y-345515D01*
X381877Y-345500D01*
X381892Y-345483D01*
X381909Y-345468D01*
X381924Y-345450D01*
X381932Y-345444D01*
X381941Y-345436D01*
X381956Y-345418D01*
X381969Y-345407D01*
X381974Y-345403D01*
X381989Y-345386D01*
X382006Y-345371D01*
X382021Y-345354D01*
X382038Y-345339D01*
X382042Y-345334D01*
X382053Y-345321D01*
X382070Y-345306D01*
X382085Y-345289D01*
X382103Y-345274D01*
X382118Y-345257D01*
X382125Y-345250D01*
X382135Y-345242D01*
X382150Y-345225D01*
X382167Y-345210D01*
X382182Y-345192D01*
X382199Y-345177D01*
X382214Y-345160D01*
X382232Y-345145D01*
X382247Y-345128D01*
X382264Y-345113D01*
X382279Y-345096D01*
X382296Y-345080D01*
X382298Y-345079D01*
X382312Y-345050D01*
X382341Y-345006D01*
X382376Y-344967D01*
X382393Y-344952D01*
X382408Y-344934D01*
X382416Y-344927D01*
X382425Y-344919D01*
X382440Y-344902D01*
X382457Y-344887D01*
X382473Y-344870D01*
X382490Y-344855D01*
X382491Y-344853D01*
X382506Y-344824D01*
X382512Y-344814D01*
X382515Y-344806D01*
X382516Y-344803D01*
Y-344798D01*
Y-344766D01*
Y-344734D01*
Y-344702D01*
Y-344669D01*
Y-344637D01*
Y-344605D01*
Y-344572D01*
Y-344540D01*
Y-344508D01*
Y-344476D01*
Y-344443D01*
Y-344411D01*
Y-344379D01*
Y-344347D01*
Y-344314D01*
Y-344282D01*
Y-344250D01*
Y-344218D01*
Y-344185D01*
Y-344153D01*
Y-344121D01*
Y-344089D01*
Y-344056D01*
Y-344024D01*
Y-343992D01*
Y-343959D01*
Y-343927D01*
Y-343895D01*
Y-343863D01*
Y-343830D01*
Y-343798D01*
Y-343766D01*
Y-343734D01*
Y-343701D01*
Y-343669D01*
Y-343637D01*
Y-343605D01*
Y-343572D01*
Y-343540D01*
Y-343508D01*
Y-343476D01*
Y-343443D01*
Y-343411D01*
Y-343379D01*
Y-343347D01*
Y-343314D01*
Y-343282D01*
Y-343250D01*
Y-343217D01*
Y-343185D01*
Y-343153D01*
Y-343121D01*
Y-343089D01*
Y-343056D01*
Y-343024D01*
Y-342992D01*
Y-342959D01*
Y-342927D01*
Y-342895D01*
Y-342863D01*
Y-342830D01*
Y-342798D01*
Y-342766D01*
Y-342734D01*
Y-342701D01*
Y-342669D01*
Y-342637D01*
Y-342604D01*
Y-342572D01*
Y-342568D01*
X382515Y-342564D01*
X382498Y-342515D01*
X382492Y-342488D01*
X382491Y-342485D01*
X382490Y-342484D01*
X382473Y-342469D01*
X382457Y-342452D01*
X382440Y-342436D01*
X382425Y-342419D01*
X382408Y-342404D01*
X382397Y-342391D01*
X382393Y-342387D01*
X382376Y-342372D01*
X382361Y-342355D01*
X382344Y-342339D01*
X382342Y-342337D01*
X382328Y-342322D01*
X382311Y-342307D01*
X382296Y-342290D01*
X382279Y-342275D01*
X382264Y-342258D01*
X382247Y-342243D01*
X382232Y-342226D01*
X382232Y-342226D01*
X382214Y-342211D01*
X382213Y-342209D01*
X382199Y-342193D01*
X382182Y-342178D01*
X382167Y-342161D01*
X382150Y-342146D01*
X382137Y-342131D01*
X382135Y-342129D01*
X382118Y-342114D01*
X382103Y-342096D01*
X382085Y-342081D01*
X382070Y-342064D01*
X382053Y-342049D01*
X382052Y-342048D01*
X382038Y-342032D01*
X382021Y-342017D01*
X382011Y-342006D01*
X382006Y-342000D01*
X381989Y-341985D01*
X381974Y-341968D01*
X381956Y-341952D01*
X381941Y-341935D01*
X381924Y-341920D01*
X381909Y-341903D01*
X381892Y-341888D01*
X381877Y-341871D01*
X381860Y-341856D01*
X381844Y-341839D01*
X381827Y-341823D01*
X381812Y-341806D01*
X381795Y-341791D01*
X381780Y-341774D01*
X381763Y-341759D01*
X381748Y-341742D01*
X381731Y-341727D01*
X381715Y-341709D01*
X381714Y-341708D01*
X381711Y-341707D01*
X381684Y-341701D01*
X381635Y-341684D01*
X381631Y-341683D01*
X381627D01*
X381575Y-341679D01*
X381523Y-341669D01*
X381473Y-341652D01*
X381470Y-341650D01*
D02*
G37*
G36*
X369210D02*
X365653D01*
X365649Y-341652D01*
X365600Y-341669D01*
X365573Y-341674D01*
X365553Y-341684D01*
X365503Y-341701D01*
X365476Y-341707D01*
X365474Y-341708D01*
X365472Y-341709D01*
X365458Y-341725D01*
X365457Y-341727D01*
X365440Y-341742D01*
X365435Y-341747D01*
X365424Y-341759D01*
X365407Y-341774D01*
X365392Y-341791D01*
X365375Y-341806D01*
X365360Y-341823D01*
X365343Y-341838D01*
X365328Y-341856D01*
X365311Y-341871D01*
X365305Y-341877D01*
X365296Y-341888D01*
X365278Y-341903D01*
X365263Y-341920D01*
X365246Y-341935D01*
X365231Y-341952D01*
X365214Y-341968D01*
X365199Y-341985D01*
X365181Y-342000D01*
X365166Y-342017D01*
X365149Y-342032D01*
X365142Y-342041D01*
X365134Y-342049D01*
X365117Y-342064D01*
X365102Y-342081D01*
X365085Y-342096D01*
X365076Y-342107D01*
X365070Y-342114D01*
X365052Y-342129D01*
X365037Y-342146D01*
X365020Y-342161D01*
X365005Y-342178D01*
X364988Y-342193D01*
X364973Y-342211D01*
X364956Y-342226D01*
X364941Y-342243D01*
X364923Y-342258D01*
X364908Y-342275D01*
X364891Y-342290D01*
X364876Y-342307D01*
X364859Y-342322D01*
X364844Y-342339D01*
X364827Y-342355D01*
X364811Y-342372D01*
X364794Y-342387D01*
X364779Y-342404D01*
X364763Y-342419D01*
X364762Y-342419D01*
X364747Y-342436D01*
X364730Y-342451D01*
X364715Y-342469D01*
X364701Y-342481D01*
X364701Y-342484D01*
X364700Y-342495D01*
X364689Y-342547D01*
X364673Y-342597D01*
X364671Y-342600D01*
Y-342604D01*
Y-342637D01*
Y-342669D01*
Y-342701D01*
Y-342734D01*
Y-342766D01*
Y-342798D01*
Y-342830D01*
Y-342863D01*
Y-342895D01*
Y-342927D01*
Y-342959D01*
Y-342992D01*
Y-343024D01*
Y-343056D01*
Y-343089D01*
Y-343121D01*
Y-343153D01*
Y-343185D01*
Y-343217D01*
Y-343250D01*
Y-343282D01*
Y-343314D01*
Y-343347D01*
Y-343379D01*
Y-343411D01*
Y-343443D01*
Y-343476D01*
Y-343508D01*
Y-343540D01*
Y-343572D01*
Y-343605D01*
Y-343637D01*
Y-343669D01*
Y-343701D01*
Y-343734D01*
Y-343766D01*
Y-343798D01*
Y-343830D01*
Y-343863D01*
Y-343895D01*
Y-343927D01*
Y-343959D01*
Y-343992D01*
Y-344024D01*
Y-344056D01*
Y-344089D01*
Y-344121D01*
Y-344153D01*
Y-344185D01*
Y-344218D01*
Y-344250D01*
Y-344282D01*
Y-344314D01*
Y-344347D01*
Y-344379D01*
Y-344411D01*
Y-344443D01*
Y-344476D01*
Y-344508D01*
Y-344540D01*
Y-344572D01*
Y-344605D01*
Y-344637D01*
Y-344669D01*
Y-344702D01*
Y-344734D01*
Y-344766D01*
Y-344798D01*
Y-344831D01*
Y-344863D01*
D01*
Y-344895D01*
Y-344927D01*
Y-344960D01*
Y-344992D01*
Y-345024D01*
Y-345056D01*
Y-345089D01*
Y-345121D01*
Y-345153D01*
Y-345185D01*
Y-345218D01*
Y-345250D01*
Y-345282D01*
Y-345315D01*
Y-345347D01*
Y-345379D01*
Y-345411D01*
Y-345444D01*
Y-345476D01*
Y-345508D01*
Y-345540D01*
Y-345573D01*
Y-345605D01*
Y-345637D01*
Y-345669D01*
Y-345702D01*
Y-345734D01*
Y-345766D01*
Y-345798D01*
Y-345831D01*
Y-345863D01*
Y-345895D01*
Y-345928D01*
Y-345960D01*
Y-345992D01*
Y-346024D01*
Y-346057D01*
Y-346089D01*
Y-346121D01*
Y-346153D01*
Y-346186D01*
Y-346218D01*
Y-346250D01*
Y-346282D01*
Y-346315D01*
Y-346347D01*
Y-346379D01*
Y-346411D01*
Y-346444D01*
Y-346476D01*
Y-346508D01*
Y-346540D01*
Y-346573D01*
Y-346605D01*
Y-346637D01*
Y-346670D01*
Y-346702D01*
Y-346734D01*
Y-346766D01*
Y-346799D01*
Y-346831D01*
Y-346863D01*
Y-346895D01*
Y-346928D01*
Y-346960D01*
Y-346964D01*
X364673Y-346968D01*
X364689Y-347017D01*
X364694Y-347043D01*
X364695Y-347044D01*
X364696Y-347047D01*
X364698Y-347048D01*
X364715Y-347064D01*
X364730Y-347081D01*
X364747Y-347096D01*
X364762Y-347113D01*
X364779Y-347128D01*
X364794Y-347145D01*
X364811Y-347160D01*
X364825Y-347176D01*
X364827Y-347178D01*
X364844Y-347193D01*
X364859Y-347210D01*
X364876Y-347225D01*
X364886Y-347236D01*
X364891Y-347242D01*
X364908Y-347257D01*
X364923Y-347274D01*
X364941Y-347289D01*
X364956Y-347307D01*
X364973Y-347322D01*
X364986Y-347337D01*
X364988Y-347339D01*
X365005Y-347354D01*
X365020Y-347371D01*
X365037Y-347386D01*
X365053Y-347403D01*
X365070Y-347418D01*
X365070Y-347418D01*
X365085Y-347436D01*
X365102Y-347451D01*
X365117Y-347468D01*
X365134Y-347483D01*
X365134Y-347483D01*
X365149Y-347500D01*
X365166Y-347515D01*
X365181Y-347532D01*
X365199Y-347548D01*
X365214Y-347565D01*
X365231Y-347580D01*
X365246Y-347597D01*
X365263Y-347612D01*
X365278Y-347629D01*
X365296Y-347644D01*
X365311Y-347661D01*
X365328Y-347676D01*
X365343Y-347694D01*
X365360Y-347709D01*
X365375Y-347726D01*
X365392Y-347741D01*
X365402Y-347752D01*
X365407Y-347758D01*
X365424Y-347773D01*
X365440Y-347791D01*
X365457Y-347806D01*
X365472Y-347823D01*
X365489Y-347838D01*
X365504Y-347855D01*
X365506Y-347856D01*
X365509Y-347858D01*
X365535Y-347863D01*
X365585Y-347880D01*
X365588Y-347882D01*
X369225D01*
Y-347863D01*
Y-347831D01*
Y-347799D01*
Y-347766D01*
Y-347734D01*
Y-347702D01*
Y-347670D01*
Y-347637D01*
Y-347605D01*
Y-347573D01*
Y-347541D01*
Y-347508D01*
Y-347476D01*
Y-347444D01*
Y-347411D01*
Y-347379D01*
Y-347347D01*
Y-347315D01*
Y-347283D01*
Y-347250D01*
Y-347218D01*
Y-347186D01*
Y-347153D01*
Y-347121D01*
Y-347089D01*
Y-347057D01*
Y-347024D01*
Y-346992D01*
Y-346974D01*
X366141D01*
X366089Y-346970D01*
X366037Y-346960D01*
X365988Y-346943D01*
X365941Y-346920D01*
X365931Y-346914D01*
X365923Y-346911D01*
X365876Y-346888D01*
X365833Y-346859D01*
X365793Y-346824D01*
X365759Y-346784D01*
X365729Y-346741D01*
X365706Y-346694D01*
X365704Y-346686D01*
X365697Y-346676D01*
X365674Y-346629D01*
X365657Y-346580D01*
X365647Y-346528D01*
X365644Y-346476D01*
Y-346444D01*
Y-346411D01*
Y-346379D01*
Y-346347D01*
Y-346315D01*
Y-346282D01*
Y-346250D01*
Y-346218D01*
Y-346186D01*
Y-346153D01*
Y-346121D01*
Y-346089D01*
Y-346057D01*
Y-346024D01*
Y-345992D01*
Y-345960D01*
Y-345928D01*
Y-345895D01*
Y-345863D01*
Y-345831D01*
Y-345798D01*
Y-345766D01*
Y-345734D01*
Y-345702D01*
Y-345669D01*
Y-345637D01*
Y-345605D01*
Y-345573D01*
Y-345540D01*
Y-345508D01*
Y-345476D01*
Y-345444D01*
Y-345411D01*
Y-345379D01*
Y-345347D01*
Y-345315D01*
Y-345282D01*
Y-345250D01*
Y-345218D01*
Y-345185D01*
Y-345153D01*
Y-345121D01*
Y-345089D01*
Y-345056D01*
Y-345024D01*
Y-344992D01*
Y-344960D01*
Y-344927D01*
Y-344895D01*
Y-344863D01*
D01*
Y-344831D01*
Y-344798D01*
Y-344766D01*
Y-344734D01*
Y-344702D01*
Y-344669D01*
Y-344637D01*
Y-344605D01*
Y-344572D01*
Y-344540D01*
Y-344508D01*
Y-344476D01*
Y-344443D01*
Y-344411D01*
Y-344379D01*
Y-344347D01*
Y-344314D01*
Y-344282D01*
Y-344250D01*
Y-344218D01*
Y-344185D01*
Y-344153D01*
Y-344121D01*
Y-344089D01*
Y-344056D01*
Y-344024D01*
Y-343992D01*
Y-343959D01*
Y-343927D01*
Y-343895D01*
Y-343863D01*
Y-343830D01*
Y-343798D01*
Y-343766D01*
Y-343734D01*
Y-343701D01*
Y-343669D01*
Y-343637D01*
Y-343605D01*
Y-343572D01*
Y-343540D01*
Y-343508D01*
Y-343476D01*
Y-343443D01*
Y-343411D01*
Y-343379D01*
Y-343347D01*
Y-343314D01*
Y-343282D01*
Y-343250D01*
Y-343217D01*
Y-343185D01*
Y-343153D01*
Y-343121D01*
Y-343089D01*
Y-343056D01*
X365647Y-343004D01*
X365657Y-342952D01*
X365674Y-342903D01*
X365697Y-342856D01*
X365726Y-342812D01*
X365761Y-342773D01*
X365778Y-342758D01*
X365793Y-342741D01*
X365810Y-342725D01*
X365826Y-342708D01*
X365865Y-342674D01*
X365909Y-342645D01*
X365955Y-342621D01*
X366005Y-342604D01*
X366057Y-342594D01*
X366109Y-342591D01*
X369146D01*
X369149Y-342589D01*
X369199Y-342572D01*
X369225Y-342567D01*
Y-342540D01*
Y-342508D01*
Y-342476D01*
Y-342443D01*
Y-342411D01*
Y-342379D01*
Y-342346D01*
Y-342314D01*
Y-342282D01*
Y-342250D01*
Y-342217D01*
Y-342185D01*
Y-342153D01*
Y-342121D01*
Y-342088D01*
Y-342056D01*
Y-342024D01*
Y-341992D01*
Y-341959D01*
Y-341927D01*
Y-341895D01*
Y-341863D01*
Y-341830D01*
Y-341798D01*
Y-341766D01*
Y-341734D01*
Y-341701D01*
Y-341669D01*
Y-341656D01*
X369214Y-341652D01*
X369210Y-341650D01*
D02*
G37*
G36*
X356191Y-347812D02*
X355685D01*
X355698Y-347824D01*
X355728Y-347839D01*
X355771Y-347868D01*
X355810Y-347902D01*
X355826Y-347920D01*
X355843Y-347935D01*
X355858Y-347952D01*
X355875Y-347967D01*
X355890Y-347984D01*
X355907Y-347999D01*
X355922Y-348016D01*
X355940Y-348031D01*
X355955Y-348049D01*
X355972Y-348064D01*
X355987Y-348081D01*
X356004Y-348096D01*
X356019Y-348113D01*
X356036Y-348128D01*
X356051Y-348145D01*
X356069Y-348161D01*
X356103Y-348200D01*
X356132Y-348243D01*
X356147Y-348273D01*
X356168Y-348297D01*
X356191Y-348331D01*
Y-348315D01*
Y-348283D01*
Y-348250D01*
Y-348218D01*
Y-348186D01*
Y-348154D01*
Y-348121D01*
Y-348089D01*
Y-348057D01*
Y-348025D01*
Y-347992D01*
Y-347960D01*
Y-347928D01*
Y-347896D01*
Y-347863D01*
Y-347831D01*
Y-347812D01*
D02*
G37*
G36*
Y-350021D02*
X356179Y-350034D01*
X356165Y-350064D01*
X356135Y-350108D01*
X356115Y-350131D01*
X356100Y-350161D01*
X356071Y-350204D01*
X356036Y-350244D01*
X356019Y-350259D01*
X356004Y-350276D01*
X355987Y-350291D01*
X355972Y-350308D01*
X355955Y-350323D01*
X355940Y-350341D01*
X355922Y-350356D01*
X355907Y-350373D01*
X355890Y-350388D01*
X355875Y-350405D01*
X355836Y-350440D01*
X355792Y-350469D01*
X355763Y-350483D01*
X355739Y-350504D01*
X355695Y-350533D01*
X355666Y-350548D01*
X355652Y-350559D01*
X356191D01*
Y-350541D01*
Y-350509D01*
Y-350476D01*
Y-350444D01*
Y-350412D01*
Y-350380D01*
Y-350347D01*
Y-350315D01*
Y-350283D01*
Y-350251D01*
Y-350218D01*
Y-350186D01*
Y-350154D01*
Y-350121D01*
Y-350089D01*
Y-350057D01*
Y-350025D01*
Y-350021D01*
D02*
G37*
G36*
Y-352168D02*
X355672D01*
X355707Y-352191D01*
X355730Y-352212D01*
X355760Y-352226D01*
X355803Y-352255D01*
X355843Y-352290D01*
X355858Y-352307D01*
X355875Y-352322D01*
X355890Y-352340D01*
X355907Y-352355D01*
X355922Y-352372D01*
X355940Y-352387D01*
X355955Y-352404D01*
X355972Y-352419D01*
X355987Y-352436D01*
X356004Y-352451D01*
X356019Y-352468D01*
X356036Y-352484D01*
X356051Y-352501D01*
X356069Y-352516D01*
X356103Y-352555D01*
X356132Y-352599D01*
X356147Y-352628D01*
X356168Y-352652D01*
X356191Y-352687D01*
Y-352670D01*
Y-352638D01*
Y-352606D01*
Y-352573D01*
Y-352541D01*
Y-352509D01*
Y-352477D01*
Y-352444D01*
Y-352412D01*
Y-352380D01*
Y-352348D01*
Y-352315D01*
Y-352283D01*
Y-352251D01*
Y-352219D01*
Y-352186D01*
Y-352168D01*
D02*
G37*
G36*
Y-354396D02*
X356168Y-354431D01*
X356147Y-354454D01*
X356132Y-354484D01*
X356103Y-354527D01*
X356069Y-354567D01*
X356051Y-354582D01*
X356036Y-354599D01*
X356019Y-354614D01*
X356004Y-354631D01*
X355987Y-354646D01*
X355972Y-354663D01*
X355955Y-354679D01*
X355940Y-354696D01*
X355922Y-354711D01*
X355907Y-354728D01*
X355890Y-354743D01*
X355875Y-354760D01*
X355858Y-354775D01*
X355843Y-354793D01*
X355803Y-354827D01*
X355760Y-354856D01*
X355730Y-354871D01*
X355707Y-354892D01*
X355672Y-354915D01*
X356191D01*
Y-354896D01*
Y-354864D01*
Y-354832D01*
Y-354800D01*
Y-354767D01*
Y-354735D01*
Y-354703D01*
Y-354670D01*
Y-354638D01*
Y-354606D01*
Y-354574D01*
Y-354541D01*
Y-354509D01*
Y-354477D01*
Y-354445D01*
Y-354412D01*
Y-354396D01*
D02*
G37*
%LPD*%
G36*
X388002Y-342562D02*
X388054Y-342572D01*
X388104Y-342589D01*
X388151Y-342612D01*
X388160Y-342619D01*
X388168Y-342621D01*
X388215Y-342645D01*
X388259Y-342674D01*
X388298Y-342708D01*
X388333Y-342748D01*
X388362Y-342791D01*
X388385Y-342838D01*
X388402Y-342888D01*
X388412Y-342939D01*
X388416Y-342992D01*
Y-343024D01*
Y-343056D01*
Y-343089D01*
Y-343121D01*
Y-343153D01*
Y-343185D01*
Y-343217D01*
Y-343250D01*
Y-343282D01*
Y-343314D01*
Y-343347D01*
Y-343379D01*
Y-343411D01*
Y-343443D01*
Y-343476D01*
Y-343508D01*
Y-343540D01*
Y-343572D01*
Y-343605D01*
Y-343637D01*
Y-343669D01*
Y-343701D01*
Y-343734D01*
Y-343766D01*
Y-343798D01*
Y-343830D01*
Y-343863D01*
Y-343895D01*
Y-343927D01*
Y-343959D01*
Y-343992D01*
Y-344024D01*
Y-344056D01*
Y-344089D01*
Y-344121D01*
Y-344153D01*
Y-344185D01*
Y-344218D01*
Y-344250D01*
Y-344282D01*
Y-344314D01*
Y-344347D01*
Y-344379D01*
Y-344411D01*
Y-344443D01*
Y-344476D01*
Y-344508D01*
Y-344540D01*
Y-344572D01*
Y-344605D01*
Y-344637D01*
Y-344669D01*
Y-344702D01*
Y-344734D01*
Y-344766D01*
Y-344798D01*
Y-344831D01*
Y-344863D01*
Y-344895D01*
Y-344927D01*
Y-344960D01*
Y-344992D01*
Y-345024D01*
Y-345056D01*
Y-345089D01*
Y-345121D01*
Y-345153D01*
Y-345185D01*
Y-345218D01*
Y-345250D01*
Y-345282D01*
Y-345315D01*
Y-345347D01*
Y-345379D01*
Y-345411D01*
Y-345444D01*
Y-345476D01*
Y-345508D01*
Y-345540D01*
Y-345573D01*
Y-345605D01*
Y-345637D01*
Y-345669D01*
Y-345702D01*
Y-345734D01*
Y-345766D01*
Y-345798D01*
Y-345831D01*
Y-345863D01*
Y-345895D01*
Y-345928D01*
Y-345960D01*
Y-345992D01*
Y-346024D01*
Y-346057D01*
Y-346089D01*
Y-346121D01*
Y-346153D01*
Y-346186D01*
Y-346218D01*
Y-346250D01*
Y-346282D01*
Y-346315D01*
Y-346347D01*
Y-346379D01*
Y-346411D01*
Y-346444D01*
Y-346476D01*
Y-346508D01*
Y-346540D01*
Y-346573D01*
X388412Y-346625D01*
X388402Y-346676D01*
X388385Y-346726D01*
X388362Y-346773D01*
X388333Y-346817D01*
X388298Y-346856D01*
X388259Y-346891D01*
X388215Y-346920D01*
X388168Y-346943D01*
X388118Y-346960D01*
X388067Y-346970D01*
X388015Y-346974D01*
X385660D01*
X385607Y-346970D01*
X385556Y-346960D01*
X385506Y-346943D01*
X385459Y-346920D01*
X385416Y-346891D01*
X385376Y-346856D01*
X385342Y-346817D01*
X385312Y-346773D01*
X385289Y-346726D01*
X385272Y-346676D01*
X385262Y-346625D01*
X385259Y-346573D01*
Y-346540D01*
Y-346508D01*
Y-346476D01*
Y-346444D01*
Y-346411D01*
Y-346379D01*
Y-346347D01*
Y-346315D01*
Y-346282D01*
Y-346250D01*
Y-346218D01*
Y-346186D01*
Y-346153D01*
Y-346121D01*
Y-346089D01*
Y-346057D01*
Y-346024D01*
Y-345992D01*
Y-345960D01*
Y-345928D01*
Y-345895D01*
Y-345863D01*
Y-345831D01*
Y-345798D01*
Y-345766D01*
Y-345734D01*
Y-345702D01*
Y-345669D01*
Y-345637D01*
Y-345605D01*
Y-345573D01*
Y-345540D01*
Y-345508D01*
Y-345476D01*
Y-345444D01*
Y-345411D01*
Y-345379D01*
Y-345347D01*
Y-345315D01*
Y-345282D01*
Y-345250D01*
Y-345218D01*
Y-345185D01*
Y-345153D01*
Y-345121D01*
Y-345089D01*
Y-345056D01*
Y-345024D01*
Y-344992D01*
Y-344960D01*
Y-344927D01*
Y-344895D01*
Y-344863D01*
Y-344831D01*
Y-344798D01*
Y-344766D01*
Y-344734D01*
Y-344702D01*
Y-344669D01*
Y-344637D01*
Y-344605D01*
Y-344572D01*
Y-344540D01*
Y-344508D01*
Y-344476D01*
Y-344443D01*
Y-344411D01*
Y-344379D01*
Y-344347D01*
Y-344314D01*
Y-344282D01*
Y-344250D01*
Y-344218D01*
Y-344185D01*
Y-344153D01*
Y-344121D01*
Y-344089D01*
Y-344056D01*
Y-344024D01*
Y-343992D01*
Y-343959D01*
Y-343927D01*
Y-343895D01*
Y-343863D01*
Y-343830D01*
Y-343798D01*
Y-343766D01*
Y-343734D01*
Y-343701D01*
Y-343669D01*
Y-343637D01*
Y-343605D01*
Y-343572D01*
Y-343540D01*
Y-343508D01*
Y-343476D01*
Y-343443D01*
Y-343411D01*
Y-343379D01*
Y-343347D01*
Y-343314D01*
Y-343282D01*
Y-343250D01*
Y-343217D01*
Y-343185D01*
Y-343153D01*
Y-343121D01*
Y-343089D01*
Y-343056D01*
Y-343024D01*
Y-342992D01*
X385262Y-342939D01*
X385272Y-342888D01*
X385289Y-342838D01*
X385312Y-342791D01*
X385342Y-342748D01*
X385376Y-342708D01*
X385393Y-342693D01*
X385408Y-342676D01*
X385448Y-342641D01*
X385491Y-342612D01*
X385538Y-342589D01*
X385588Y-342572D01*
X385640Y-342562D01*
X385692Y-342559D01*
X385724D01*
X385776Y-342562D01*
X385828Y-342572D01*
X385877Y-342589D01*
X385881Y-342591D01*
X387664D01*
X387668Y-342589D01*
X387717Y-342572D01*
X387769Y-342562D01*
X387821Y-342559D01*
X387853D01*
X387886Y-342561D01*
X387918Y-342559D01*
X387950D01*
X388002Y-342562D01*
D02*
G37*
G36*
X381195Y-342497D02*
X381247Y-342508D01*
X381296Y-342525D01*
X381343Y-342548D01*
X381387Y-342577D01*
X381426Y-342611D01*
X381461Y-342651D01*
X381490Y-342694D01*
X381513Y-342741D01*
X381530Y-342791D01*
X381540Y-342843D01*
X381544Y-342895D01*
Y-342927D01*
Y-342959D01*
Y-342992D01*
Y-343024D01*
Y-343056D01*
Y-343089D01*
Y-343121D01*
Y-343153D01*
Y-343185D01*
Y-343217D01*
Y-343250D01*
Y-343282D01*
Y-343314D01*
Y-343347D01*
Y-343379D01*
Y-343411D01*
Y-343443D01*
Y-343476D01*
Y-343508D01*
Y-343540D01*
Y-343572D01*
Y-343605D01*
Y-343637D01*
Y-343669D01*
Y-343701D01*
Y-343734D01*
Y-343766D01*
Y-343798D01*
Y-343830D01*
Y-343863D01*
Y-343895D01*
Y-343927D01*
Y-343959D01*
Y-343992D01*
Y-344024D01*
Y-344056D01*
Y-344089D01*
Y-344121D01*
Y-344153D01*
Y-344185D01*
Y-344218D01*
Y-344250D01*
Y-344282D01*
Y-344314D01*
Y-344347D01*
Y-344379D01*
Y-344411D01*
Y-344443D01*
Y-344476D01*
Y-344508D01*
Y-344540D01*
Y-344572D01*
Y-344605D01*
X381540Y-344657D01*
X381530Y-344708D01*
X381513Y-344758D01*
X381490Y-344805D01*
X381461Y-344849D01*
X381426Y-344888D01*
X381387Y-344923D01*
X381343Y-344952D01*
X381296Y-344975D01*
X381247Y-344992D01*
X381195Y-345002D01*
X381143Y-345006D01*
X378723D01*
X378671Y-345002D01*
X378620Y-344992D01*
X378570Y-344975D01*
X378523Y-344952D01*
X378479Y-344923D01*
X378440Y-344888D01*
X378405Y-344849D01*
X378376Y-344805D01*
X378353Y-344758D01*
X378336Y-344708D01*
X378326Y-344657D01*
X378322Y-344605D01*
Y-344572D01*
Y-344540D01*
Y-344508D01*
Y-344476D01*
Y-344443D01*
Y-344411D01*
Y-344379D01*
Y-344347D01*
Y-344314D01*
Y-344282D01*
Y-344250D01*
Y-344218D01*
Y-344185D01*
Y-344153D01*
Y-344121D01*
Y-344089D01*
Y-344056D01*
Y-344024D01*
Y-343992D01*
Y-343959D01*
Y-343927D01*
Y-343895D01*
Y-343863D01*
Y-343830D01*
Y-343798D01*
Y-343766D01*
Y-343734D01*
Y-343701D01*
Y-343669D01*
Y-343637D01*
Y-343605D01*
Y-343572D01*
Y-343540D01*
Y-343508D01*
Y-343476D01*
Y-343443D01*
Y-343411D01*
Y-343379D01*
Y-343347D01*
Y-343314D01*
Y-343282D01*
Y-343250D01*
Y-343217D01*
Y-343185D01*
Y-343153D01*
Y-343121D01*
Y-343089D01*
Y-343056D01*
Y-343024D01*
Y-342992D01*
Y-342959D01*
Y-342927D01*
Y-342895D01*
X378326Y-342843D01*
X378336Y-342791D01*
X378353Y-342741D01*
X378376Y-342694D01*
X378405Y-342651D01*
X378440Y-342611D01*
X378479Y-342577D01*
X378523Y-342548D01*
X378570Y-342525D01*
X378620Y-342508D01*
X378671Y-342497D01*
X378723Y-342494D01*
X381143D01*
X381195Y-342497D01*
D02*
G37*
D12*
X690534Y-294457D02*
X694033D01*
X695199Y-293290D01*
X694033Y-292124D01*
X695199Y-290958D01*
X694033Y-289792D01*
X690534D01*
Y-287459D02*
X694033D01*
X695199Y-286293D01*
X694033Y-285126D01*
X695199Y-283960D01*
X694033Y-282794D01*
X690534D01*
Y-280461D02*
X694033D01*
X695199Y-279295D01*
X694033Y-278129D01*
X695199Y-276962D01*
X694033Y-275796D01*
X690534D01*
X695199Y-273464D02*
X694033D01*
Y-272297D01*
X695199D01*
Y-273464D01*
X689367Y-266466D02*
X690534D01*
Y-267632D01*
Y-265300D01*
Y-266466D01*
X694033D01*
X695199Y-265300D01*
Y-261801D02*
Y-259468D01*
Y-260634D01*
X690534D01*
Y-261801D01*
X695199Y-255969D02*
X690534D01*
Y-254803D01*
X691700Y-253637D01*
X695199D01*
X691700D01*
X690534Y-252470D01*
X691700Y-251304D01*
X695199D01*
Y-248971D02*
Y-246639D01*
Y-247805D01*
X690534D01*
Y-248971D01*
X695199Y-243140D02*
X690534D01*
Y-239641D01*
X691700Y-238475D01*
X695199D01*
X697532Y-233810D02*
Y-232643D01*
X696365Y-231477D01*
X690534D01*
Y-234976D01*
X691700Y-236142D01*
X694033D01*
X695199Y-234976D01*
Y-231477D01*
X690534Y-224479D02*
Y-227978D01*
X691700Y-229145D01*
X694033D01*
X695199Y-227978D01*
Y-224479D01*
X690534Y-220980D02*
Y-218648D01*
X691700Y-217482D01*
X695199D01*
Y-220980D01*
X694033Y-222147D01*
X692866Y-220980D01*
Y-217482D01*
X690534Y-215149D02*
X695199D01*
X692866D01*
X691700Y-213983D01*
X690534Y-212816D01*
Y-211650D01*
X688201Y-203486D02*
X695199D01*
Y-206985D01*
X694033Y-208151D01*
X691700D01*
X690534Y-206985D01*
Y-203486D01*
X695199Y-201153D02*
X694033D01*
Y-199987D01*
X695199D01*
Y-201153D01*
X690534Y-190657D02*
Y-194156D01*
X691700Y-195322D01*
X694033D01*
X695199Y-194156D01*
Y-190657D01*
Y-187158D02*
Y-184826D01*
X694033Y-183659D01*
X691700D01*
X690534Y-184826D01*
Y-187158D01*
X691700Y-188324D01*
X694033D01*
X695199Y-187158D01*
Y-181327D02*
X690534D01*
Y-180160D01*
X691700Y-178994D01*
X695199D01*
X691700D01*
X690534Y-177828D01*
X691700Y-176661D01*
X695199D01*
D28*
X171791Y-344590D02*
Y-349588D01*
X173458Y-351254D01*
X175124Y-349588D01*
X176790Y-351254D01*
X178456Y-349588D01*
Y-344590D01*
X181788D02*
Y-349588D01*
X183454Y-351254D01*
X185120Y-349588D01*
X186786Y-351254D01*
X188453Y-349588D01*
Y-344590D01*
X191785D02*
Y-349588D01*
X193451Y-351254D01*
X195117Y-349588D01*
X196783Y-351254D01*
X198449Y-349588D01*
Y-344590D01*
X201782Y-351254D02*
Y-349588D01*
X203448D01*
Y-351254D01*
X201782D01*
X211778Y-342924D02*
Y-344590D01*
X210112D01*
X213444D01*
X211778D01*
Y-349588D01*
X213444Y-351254D01*
X218443D02*
X221775D01*
X220109D01*
Y-344590D01*
X218443D01*
X226774Y-351254D02*
Y-344590D01*
X228440D01*
X230106Y-346256D01*
Y-351254D01*
Y-346256D01*
X231772Y-344590D01*
X233438Y-346256D01*
Y-351254D01*
X236770D02*
X240103D01*
X238437D01*
Y-344590D01*
X236770D01*
X245101Y-351254D02*
Y-344590D01*
X250099D01*
X251765Y-346256D01*
Y-351254D01*
X258430Y-354587D02*
X260096D01*
X261762Y-352921D01*
Y-344590D01*
X256764D01*
X255098Y-346256D01*
Y-349588D01*
X256764Y-351254D01*
X261762D01*
X271759Y-344590D02*
X266761D01*
X265094Y-346256D01*
Y-349588D01*
X266761Y-351254D01*
X271759D01*
X276757Y-344590D02*
X280090D01*
X281756Y-346256D01*
Y-351254D01*
X276757D01*
X275091Y-349588D01*
X276757Y-347922D01*
X281756D01*
X285088Y-344590D02*
Y-351254D01*
Y-347922D01*
X286754Y-346256D01*
X288420Y-344590D01*
X290086D01*
X301749Y-341258D02*
Y-351254D01*
X296751D01*
X295085Y-349588D01*
Y-346256D01*
X296751Y-344590D01*
X301749D01*
X305082Y-351254D02*
Y-349588D01*
X306748D01*
Y-351254D01*
X305082D01*
X320077Y-344590D02*
X315078D01*
X313412Y-346256D01*
Y-349588D01*
X315078Y-351254D01*
X320077D01*
X325075D02*
X328407D01*
X330073Y-349588D01*
Y-346256D01*
X328407Y-344590D01*
X325075D01*
X323409Y-346256D01*
Y-349588D01*
X325075Y-351254D01*
X333406D02*
Y-344590D01*
X335072D01*
X336738Y-346256D01*
Y-351254D01*
Y-346256D01*
X338404Y-344590D01*
X340070Y-346256D01*
Y-351254D01*
D36*
X685827Y-29577D02*
D03*
Y-25541D02*
D03*
D38*
X553504Y-244882D02*
D03*
X577205D02*
D03*
X605472Y-191339D02*
D03*
X629173D02*
D03*
X655158Y-254331D02*
D03*
X631457D02*
D03*
D39*
X601492Y-275984D02*
D03*
X624492D02*
D03*
X628035Y-215748D02*
D03*
X605035D02*
D03*
D43*
X688197Y-322441D02*
D03*
X684243D02*
D03*
X688197Y-315748D02*
D03*
X684243D02*
D03*
D44*
X675787Y-323228D02*
D03*
X669882D02*
D03*
X675787Y-315748D02*
D03*
X669882D02*
D03*
D48*
X681102Y-83858D02*
D03*
Y-86417D02*
D03*
Y-88976D02*
D03*
Y-91535D02*
D03*
Y-94095D02*
D03*
D49*
X681004Y-47577D02*
D03*
X682776D02*
D03*
X684547D02*
D03*
X686319D02*
D03*
X688091D02*
D03*
X689862D02*
D03*
Y-58723D02*
D03*
X688091D02*
D03*
X686319D02*
D03*
X684547D02*
D03*
X682776D02*
D03*
D50*
X681004D02*
D03*
D51*
X672441Y-106992D02*
D03*
Y-100882D02*
D03*
D53*
X662683Y-110630D02*
D03*
X665664D02*
D03*
X589848Y-237402D02*
D03*
X592829D02*
D03*
X500309Y-109843D02*
D03*
X497329D02*
D03*
D54*
X695140Y-66142D02*
D03*
X692262D02*
D03*
X628998Y-93307D02*
D03*
X626120D02*
D03*
X551439Y-279921D02*
D03*
X548561D02*
D03*
X640293Y-277953D02*
D03*
X643171D02*
D03*
D55*
X667717Y-94488D02*
D03*
X671654D02*
D03*
D56*
X679528Y-29921D02*
D03*
Y-33858D02*
D03*
X560236Y-201575D02*
D03*
Y-197638D02*
D03*
X547835Y-261614D02*
D03*
Y-257677D02*
D03*
D57*
X686614Y-36356D02*
D03*
Y-39234D02*
D03*
X694095Y-36492D02*
D03*
Y-39370D02*
D03*
X597244Y-90687D02*
D03*
Y-93565D02*
D03*
X250394Y-109191D02*
D03*
Y-112069D02*
D03*
X681890Y-208661D02*
D03*
Y-205783D02*
D03*
X562598Y-213128D02*
D03*
Y-216006D02*
D03*
D58*
X421122Y-112697D02*
D03*
X426122D02*
D03*
Y-136909D02*
D03*
X421122D02*
D03*
D59*
X409842Y-132874D02*
D03*
Y-126969D02*
D03*
X436614Y-132480D02*
D03*
Y-126575D02*
D03*
X40354Y14764D02*
D03*
Y8858D02*
D03*
X33465Y14764D02*
D03*
Y8858D02*
D03*
X26575Y14764D02*
D03*
Y8858D02*
D03*
X47244Y14764D02*
D03*
Y8858D02*
D03*
D60*
X409730Y-119764D02*
D03*
Y-115810D02*
D03*
X436614Y-120866D02*
D03*
Y-116912D02*
D03*
D62*
X660236Y-195315D02*
D03*
Y-171614D02*
D03*
D63*
X683362Y-183296D02*
D03*
Y-187064D02*
D03*
D65*
X634862Y-233858D02*
D03*
X626555D02*
D03*
X623839Y-296063D02*
D03*
X615531D02*
D03*
D66*
X650394Y-227559D02*
D03*
Y-222047D02*
D03*
X674409Y-210236D02*
D03*
Y-204724D02*
D03*
X643307Y-297638D02*
D03*
Y-292126D02*
D03*
D69*
X588793Y-215409D02*
D03*
X577618Y-274016D02*
D03*
D70*
X559533Y-221654D02*
D03*
X563301D02*
D03*
X548116Y-291732D02*
D03*
X551884D02*
D03*
X666451Y-276378D02*
D03*
X662683D02*
D03*
D73*
X599213Y-242717D02*
D03*
Y-236811D02*
D03*
D74*
X613976Y-233465D02*
D03*
X619882D02*
D03*
X597441Y-295669D02*
D03*
X603346D02*
D03*
X569488Y-291732D02*
D03*
X575394D02*
D03*
D76*
X675591Y-178150D02*
D03*
Y-191142D02*
D03*
D77*
X666929Y-209317D02*
D03*
Y-205643D02*
D03*
X553543Y-221391D02*
D03*
Y-225065D02*
D03*
D78*
X658661Y-235846D02*
D03*
Y-230847D02*
D03*
Y-225847D02*
D03*
Y-220847D02*
D03*
X679921D02*
D03*
Y-225847D02*
D03*
Y-230847D02*
D03*
Y-235846D02*
D03*
X650787Y-307500D02*
D03*
Y-302500D02*
D03*
Y-297500D02*
D03*
Y-292500D02*
D03*
X672047D02*
D03*
Y-297500D02*
D03*
Y-302500D02*
D03*
Y-307500D02*
D03*
D80*
X596063Y-183560D02*
D03*
Y-193605D02*
D03*
X586614Y-183560D02*
D03*
Y-193605D02*
D03*
X594488Y-248521D02*
D03*
Y-258566D02*
D03*
X605512Y-248914D02*
D03*
Y-258960D02*
D03*
D84*
X596063Y-147343D02*
D03*
Y-121161D02*
D03*
D85*
X551968Y-169291D02*
D03*
X577953D02*
D03*
D87*
X558137Y-292520D02*
D03*
X561811D02*
D03*
X667217Y-252303D02*
D03*
X663543D02*
D03*
D89*
X591732Y-292829D02*
D03*
Y-289848D02*
D03*
D90*
X670669Y-268504D02*
D03*
X657677D02*
D03*
D91*
X668110Y-260236D02*
D03*
X662598D02*
D03*
X531890Y-133858D02*
D03*
X537402D02*
D03*
D93*
X558681Y-137008D02*
D03*
X553681D02*
D03*
X548681D02*
D03*
X543681D02*
D03*
Y-115748D02*
D03*
X548681D02*
D03*
X553681D02*
D03*
X558681D02*
D03*
D96*
X47244Y-35433D02*
D03*
Y-43307D02*
D03*
X124409Y-37008D02*
D03*
Y-44882D02*
D03*
X89567Y-98277D02*
D03*
Y-90403D02*
D03*
X123031Y-79970D02*
D03*
Y-72096D02*
D03*
D97*
X671654Y-56693D02*
D03*
X663779D02*
D03*
X601575Y-53937D02*
D03*
X609449D02*
D03*
X673622Y-23622D02*
D03*
X665748D02*
D03*
X609252Y-21506D02*
D03*
X617126D02*
D03*
D105*
X638287Y-168504D02*
D03*
X612106D02*
D03*
D119*
X83268Y-110236D02*
D03*
X76575D02*
D03*
D120*
X75787Y-127756D02*
D03*
Y-123031D02*
D03*
D133*
X519783Y-126131D02*
D03*
Y-128691D02*
D03*
X511713D02*
D03*
Y-126131D02*
D03*
Y-123572D02*
D03*
Y-121013D02*
D03*
X519783D02*
D03*
Y-123572D02*
D03*
D134*
X464370Y-130034D02*
D03*
X456890D02*
D03*
Y-121639D02*
D03*
X460630D02*
D03*
D135*
X464370D02*
D03*
D136*
X479872Y-125394D02*
D03*
Y-123425D02*
D03*
Y-121457D02*
D03*
X498081D02*
D03*
Y-123425D02*
D03*
D137*
X479872Y-119488D02*
D03*
D138*
X498081D02*
D03*
D139*
Y-125394D02*
D03*
D140*
X480118Y-128593D02*
D03*
X484055Y-128593D02*
D03*
X487992Y-128593D02*
D03*
X489961D02*
D03*
X493898Y-128593D02*
D03*
X497835Y-128593D02*
D03*
X480118Y-116289D02*
D03*
X482087Y-116289D02*
D03*
X484055Y-116289D02*
D03*
X487992Y-116289D02*
D03*
X489961D02*
D03*
X491929Y-116289D02*
D03*
X493898Y-116289D02*
D03*
X497835Y-116289D02*
D03*
D141*
X482087Y-128593D02*
D03*
X491929D02*
D03*
D142*
X486024D02*
D03*
X495866D02*
D03*
D143*
X486024Y-116289D02*
D03*
X495866D02*
D03*
D144*
X118504Y-390698D02*
D03*
D145*
X216142Y-404084D02*
D03*
D146*
X82677Y-128740D02*
D03*
Y-123228D02*
D03*
X55905Y-42520D02*
D03*
Y-37008D02*
D03*
X111417Y-43307D02*
D03*
Y-37795D02*
D03*
X568110Y-117717D02*
D03*
Y-123228D02*
D03*
X67913Y-335433D02*
D03*
Y-329921D02*
D03*
X114173Y-73868D02*
D03*
Y-79379D02*
D03*
X98425Y-92568D02*
D03*
Y-98080D02*
D03*
X348106Y-104238D02*
D03*
Y-98726D02*
D03*
X447835Y-128592D02*
D03*
Y-123080D02*
D03*
X67913Y-169488D02*
D03*
Y-175000D02*
D03*
X68898Y-275787D02*
D03*
Y-281299D02*
D03*
X68898Y-221654D02*
D03*
Y-227165D02*
D03*
X528543Y-112057D02*
D03*
Y-117569D02*
D03*
D147*
X66142Y-113779D02*
D03*
X69291D02*
D03*
X66142Y-110236D02*
D03*
X69291D02*
D03*
X69291Y-117717D02*
D03*
X66142D02*
D03*
X551968Y-270866D02*
D03*
X548819D02*
D03*
X672047Y-242126D02*
D03*
X675197D02*
D03*
X561417Y-205512D02*
D03*
X564567D02*
D03*
X561417Y-209055D02*
D03*
X564567D02*
D03*
X550394Y-109055D02*
D03*
X553543D02*
D03*
X565748Y-109449D02*
D03*
X562598D02*
D03*
X548819Y-274803D02*
D03*
X551968D02*
D03*
X683858Y-301969D02*
D03*
X680709D02*
D03*
X683858Y-306299D02*
D03*
X680709D02*
D03*
X493307Y-109055D02*
D03*
X490158D02*
D03*
X473622Y-116929D02*
D03*
X470472D02*
D03*
X486614Y-109055D02*
D03*
X483465D02*
D03*
X505905Y-119685D02*
D03*
X502756D02*
D03*
X472835Y-134646D02*
D03*
X475984D02*
D03*
X479921Y-109055D02*
D03*
X476772D02*
D03*
X426378Y-183858D02*
D03*
X423228D02*
D03*
D148*
X662598Y-82638D02*
D03*
Y-79567D02*
D03*
X675591Y-79882D02*
D03*
Y-76811D02*
D03*
D149*
X608268Y-81890D02*
D03*
X611811D02*
D03*
X604528Y-101181D02*
D03*
X608071D02*
D03*
X581693Y-80709D02*
D03*
X585236D02*
D03*
X574016Y-106299D02*
D03*
X577559D02*
D03*
X629331Y-86614D02*
D03*
X625787D02*
D03*
X604921Y-89764D02*
D03*
X608465D02*
D03*
X629724Y-99606D02*
D03*
X626181D02*
D03*
X604921Y-95276D02*
D03*
X608465D02*
D03*
X572244Y-88189D02*
D03*
X575787D02*
D03*
X596260Y-98032D02*
D03*
X592717D02*
D03*
X571850Y-100394D02*
D03*
X575394D02*
D03*
X682087Y-41339D02*
D03*
X678543D02*
D03*
D150*
X235039Y-116831D02*
D03*
Y-113878D02*
D03*
X259842Y-118996D02*
D03*
Y-121949D02*
D03*
D151*
X240453Y-122441D02*
D03*
X237500D02*
D03*
X259350Y-104724D02*
D03*
X256398D02*
D03*
X678051Y-67716D02*
D03*
X681004D02*
D03*
X439665Y-111024D02*
D03*
X436713D02*
D03*
X406693Y-110630D02*
D03*
X409646D02*
D03*
X242618Y-114173D02*
D03*
X245571D02*
D03*
X242618Y-130709D02*
D03*
X245571D02*
D03*
X256988Y-115354D02*
D03*
X254035D02*
D03*
X255413Y-130709D02*
D03*
X252461D02*
D03*
D152*
X169488Y-109449D02*
D03*
X163583D02*
D03*
X82677Y-135827D02*
D03*
X76772D02*
D03*
X148622Y-109449D02*
D03*
X154527D02*
D03*
D153*
X266535Y-118898D02*
D03*
X271654D02*
D03*
X269488Y-129134D02*
D03*
X264370D02*
D03*
D154*
X239764Y-108268D02*
D03*
X234252D02*
D03*
X665354Y-47244D02*
D03*
X670866D02*
D03*
X608268Y-44882D02*
D03*
X602756D02*
D03*
X666142Y-16142D02*
D03*
X671654D02*
D03*
X615522Y-14017D02*
D03*
X610010D02*
D03*
X263976Y-112057D02*
D03*
X269488D02*
D03*
X518701D02*
D03*
X513189D02*
D03*
D155*
X692421Y-72342D02*
D03*
Y-105610D02*
D03*
D156*
X685433Y-53150D02*
D03*
D157*
X671260Y-82874D02*
D03*
Y-79331D02*
D03*
X594095Y-83268D02*
D03*
Y-86811D02*
D03*
X667717Y-82874D02*
D03*
Y-79331D02*
D03*
X696457Y-44685D02*
D03*
Y-48228D02*
D03*
D158*
X619685Y-90158D02*
D03*
Y-91732D02*
D03*
Y-93307D02*
D03*
Y-94882D02*
D03*
Y-96457D02*
D03*
X614567D02*
D03*
Y-94882D02*
D03*
Y-93307D02*
D03*
Y-91732D02*
D03*
X586811Y-90158D02*
D03*
Y-91732D02*
D03*
Y-93307D02*
D03*
Y-94882D02*
D03*
Y-96457D02*
D03*
X581693D02*
D03*
Y-94882D02*
D03*
Y-93307D02*
D03*
Y-91732D02*
D03*
D159*
X617126Y-96457D02*
D03*
Y-90158D02*
D03*
X584252Y-96457D02*
D03*
Y-90158D02*
D03*
D160*
X615354D02*
D03*
X582480D02*
D03*
X245276Y-123031D02*
D03*
D161*
Y-118701D02*
D03*
X246850D02*
D03*
X248425D02*
D03*
X250000D02*
D03*
X251575D02*
D03*
Y-123819D02*
D03*
X250000D02*
D03*
X248425D02*
D03*
X246850D02*
D03*
D162*
X251575Y-121260D02*
D03*
X245276D02*
D03*
D163*
X548524Y-265945D02*
D03*
X551870D02*
D03*
X134744Y-347244D02*
D03*
X131398D02*
D03*
X134744Y-342913D02*
D03*
X131398D02*
D03*
D164*
X640945Y-211122D02*
D03*
Y-200689D02*
D03*
X576772Y-150492D02*
D03*
Y-140059D02*
D03*
D165*
X614961Y-239764D02*
D03*
X618898D02*
D03*
X558661Y-286614D02*
D03*
X562598D02*
D03*
D166*
X588793Y-207929D02*
D03*
X577618Y-266535D02*
D03*
D167*
X573379Y-219838D02*
D03*
Y-217279D02*
D03*
Y-214720D02*
D03*
Y-212161D02*
D03*
Y-209602D02*
D03*
Y-207043D02*
D03*
X596214D02*
D03*
Y-209602D02*
D03*
Y-212161D02*
D03*
Y-214720D02*
D03*
Y-217279D02*
D03*
Y-219838D02*
D03*
X562205Y-278445D02*
D03*
Y-275886D02*
D03*
Y-273327D02*
D03*
Y-270768D02*
D03*
Y-268209D02*
D03*
Y-265650D02*
D03*
X585039D02*
D03*
Y-268209D02*
D03*
Y-270768D02*
D03*
Y-273327D02*
D03*
Y-275886D02*
D03*
Y-278445D02*
D03*
D168*
X575840Y-203992D02*
D03*
X578399D02*
D03*
X580958D02*
D03*
X583517D02*
D03*
X586076D02*
D03*
X588635D02*
D03*
X591194D02*
D03*
X593753D02*
D03*
Y-222889D02*
D03*
X591194D02*
D03*
X588635D02*
D03*
X586076D02*
D03*
X583517D02*
D03*
X580958D02*
D03*
X578399D02*
D03*
X575840D02*
D03*
X564665Y-262598D02*
D03*
X567224D02*
D03*
X569783D02*
D03*
X572342D02*
D03*
X574902D02*
D03*
X577461D02*
D03*
X580020D02*
D03*
X582579D02*
D03*
Y-281496D02*
D03*
X580020D02*
D03*
X577461D02*
D03*
X574902D02*
D03*
X572342D02*
D03*
X569783D02*
D03*
X567224D02*
D03*
X564665D02*
D03*
D169*
X578694Y-213440D02*
D03*
X567520Y-272047D02*
D03*
D170*
X567717Y-220079D02*
D03*
Y-224016D02*
D03*
X607874Y-293307D02*
D03*
Y-297244D02*
D03*
D171*
X594488Y-231398D02*
D03*
Y-228445D02*
D03*
X594095Y-285335D02*
D03*
Y-282382D02*
D03*
D172*
X608563Y-232283D02*
D03*
X604823D02*
D03*
X550098Y-200394D02*
D03*
X553839D02*
D03*
X581595Y-289764D02*
D03*
X585335D02*
D03*
X548228Y-285039D02*
D03*
X551968D02*
D03*
D173*
X667717Y-245276D02*
D03*
Y-242126D02*
D03*
X504724Y-109843D02*
D03*
Y-112992D02*
D03*
X508661Y-109843D02*
D03*
Y-112992D02*
D03*
X473622Y-123622D02*
D03*
Y-120472D02*
D03*
X140157Y-131102D02*
D03*
Y-127953D02*
D03*
D174*
X599213Y-231594D02*
D03*
Y-228248D02*
D03*
X566142Y-201279D02*
D03*
Y-197933D02*
D03*
X552953Y-261319D02*
D03*
Y-257972D02*
D03*
D175*
X643701Y-223858D02*
D03*
Y-227323D02*
D03*
X502756Y-123858D02*
D03*
Y-127323D02*
D03*
D176*
X554724Y-211516D02*
D03*
Y-215256D02*
D03*
D177*
X634154Y-269291D02*
D03*
X644587D02*
D03*
D178*
X581791Y-285433D02*
D03*
X585138D02*
D03*
D179*
X662835Y-283071D02*
D03*
X666299D02*
D03*
X535984Y-141339D02*
D03*
X532520D02*
D03*
X496299D02*
D03*
X499764D02*
D03*
X496299Y-137402D02*
D03*
X499764D02*
D03*
X502205Y-133465D02*
D03*
X505669D02*
D03*
D180*
X631890Y-61269D02*
D03*
Y-53395D02*
D03*
Y-45521D02*
D03*
Y-37647D02*
D03*
X649390Y-61269D02*
D03*
Y-53395D02*
D03*
Y-45521D02*
D03*
Y-69143D02*
D03*
Y-14025D02*
D03*
Y-29773D02*
D03*
Y-21899D02*
D03*
Y-37647D02*
D03*
X631890Y-14025D02*
D03*
Y-21899D02*
D03*
Y-29773D02*
D03*
Y-69143D02*
D03*
X91536Y-26427D02*
D03*
Y-34301D02*
D03*
Y-42175D02*
D03*
Y-50049D02*
D03*
X74036Y-26427D02*
D03*
Y-34301D02*
D03*
Y-42175D02*
D03*
Y-18553D02*
D03*
Y-73671D02*
D03*
Y-57923D02*
D03*
Y-65797D02*
D03*
Y-50049D02*
D03*
X91536Y-73671D02*
D03*
Y-65797D02*
D03*
Y-57923D02*
D03*
Y-18553D02*
D03*
X649390Y-14025D02*
D03*
Y-29773D02*
D03*
Y-21899D02*
D03*
Y-37647D02*
D03*
X631890Y-14025D02*
D03*
Y-21899D02*
D03*
Y-29773D02*
D03*
Y-37647D02*
D03*
X74036Y-73671D02*
D03*
Y-57923D02*
D03*
Y-65797D02*
D03*
Y-50049D02*
D03*
X91536Y-73671D02*
D03*
Y-65797D02*
D03*
Y-57923D02*
D03*
Y-50049D02*
D03*
D181*
X474906Y-308553D02*
D03*
X386914D02*
D03*
Y-160521D02*
D03*
X474906D02*
D03*
D182*
X437795Y-300625D02*
D03*
X439763D02*
D03*
X414173D02*
D03*
X398425D02*
D03*
X410236D02*
D03*
X418110D02*
D03*
X406299D02*
D03*
X427952D02*
D03*
X424015D02*
D03*
X408267Y-316569D02*
D03*
X416141D02*
D03*
X410236D02*
D03*
X398425D02*
D03*
X400393Y-300625D02*
D03*
X404330D02*
D03*
X455511D02*
D03*
X433858D02*
D03*
X414173Y-316569D02*
D03*
X404330D02*
D03*
X408267Y-300625D02*
D03*
X416141D02*
D03*
X420078D02*
D03*
X435826D02*
D03*
X400393Y-316569D02*
D03*
X425984Y-300625D02*
D03*
X429921D02*
D03*
X406299Y-316569D02*
D03*
X445669Y-300625D02*
D03*
X443700D02*
D03*
X449606Y-316569D02*
D03*
X455511D02*
D03*
X420078D02*
D03*
X418110D02*
D03*
X457480Y-300625D02*
D03*
X465354Y-316569D02*
D03*
X467322Y-300625D02*
D03*
X443700Y-316569D02*
D03*
X457480D02*
D03*
X447637D02*
D03*
X445669D02*
D03*
X439763D02*
D03*
X427952D02*
D03*
X433858D02*
D03*
X463385D02*
D03*
X453543D02*
D03*
X459448D02*
D03*
X425984D02*
D03*
X465354Y-300625D02*
D03*
X467322Y-316569D02*
D03*
X437795D02*
D03*
X424015D02*
D03*
X463385Y-300625D02*
D03*
X469291D02*
D03*
X459448D02*
D03*
X469291Y-316569D02*
D03*
X453543Y-300625D02*
D03*
X429921Y-316569D02*
D03*
X435826D02*
D03*
X449606Y-300625D02*
D03*
X396456Y-316569D02*
D03*
Y-300625D02*
D03*
X461417D02*
D03*
X451574D02*
D03*
X441732D02*
D03*
X431889D02*
D03*
X422047D02*
D03*
X412204D02*
D03*
X402362D02*
D03*
X461417Y-316569D02*
D03*
X451574D02*
D03*
X441732D02*
D03*
X431889D02*
D03*
X422047D02*
D03*
X412204D02*
D03*
X402362D02*
D03*
X392519D02*
D03*
Y-300625D02*
D03*
X394488D02*
D03*
X447637D02*
D03*
X394488Y-316569D02*
D03*
X424024Y-168449D02*
D03*
X422056D02*
D03*
X447647D02*
D03*
X463394D02*
D03*
X451584D02*
D03*
X443710D02*
D03*
X455521D02*
D03*
X433868D02*
D03*
X437805D02*
D03*
X453552Y-152505D02*
D03*
X445679D02*
D03*
X451584D02*
D03*
X463394D02*
D03*
X461427Y-168449D02*
D03*
X457489D02*
D03*
X406309D02*
D03*
X427961D02*
D03*
X447647Y-152505D02*
D03*
X457489D02*
D03*
X453552Y-168449D02*
D03*
X445679D02*
D03*
X441742D02*
D03*
X425993D02*
D03*
X461427Y-152505D02*
D03*
X435836Y-168449D02*
D03*
X431898D02*
D03*
X455521Y-152505D02*
D03*
X416151Y-168449D02*
D03*
X418119D02*
D03*
X412214Y-152505D02*
D03*
X406309D02*
D03*
X441742D02*
D03*
X443710D02*
D03*
X404340Y-168449D02*
D03*
X396465Y-152505D02*
D03*
X394498Y-168449D02*
D03*
X418119Y-152505D02*
D03*
X404340D02*
D03*
X414183D02*
D03*
X416151D02*
D03*
X422056D02*
D03*
X433868D02*
D03*
X427961D02*
D03*
X398434D02*
D03*
X408277D02*
D03*
X402372D02*
D03*
X435836D02*
D03*
X396465Y-168449D02*
D03*
X394498Y-152505D02*
D03*
X424024D02*
D03*
X437805D02*
D03*
X398434Y-168449D02*
D03*
X392529D02*
D03*
X402372D02*
D03*
X392529Y-152505D02*
D03*
X408277Y-168449D02*
D03*
X431898Y-152505D02*
D03*
X425993D02*
D03*
X412214Y-168449D02*
D03*
X465364Y-152505D02*
D03*
Y-168449D02*
D03*
X400403D02*
D03*
X410246D02*
D03*
X420088D02*
D03*
X429931D02*
D03*
X439773D02*
D03*
X449615D02*
D03*
X459457D02*
D03*
X400403Y-152505D02*
D03*
X410246D02*
D03*
X420088D02*
D03*
X429931D02*
D03*
X439773D02*
D03*
X449615D02*
D03*
X459457D02*
D03*
X469301D02*
D03*
Y-168449D02*
D03*
X467332D02*
D03*
X414183D02*
D03*
X467332Y-152505D02*
D03*
D183*
X340949Y-278041D02*
D03*
Y-190049D02*
D03*
X528351D02*
D03*
Y-278041D02*
D03*
D184*
X348876Y-240930D02*
D03*
Y-242898D02*
D03*
Y-217308D02*
D03*
Y-201560D02*
D03*
Y-213371D02*
D03*
Y-221245D02*
D03*
Y-209434D02*
D03*
Y-231087D02*
D03*
Y-227150D02*
D03*
X332932Y-211402D02*
D03*
Y-219276D02*
D03*
Y-213371D02*
D03*
Y-201560D02*
D03*
X348876Y-203528D02*
D03*
Y-207465D02*
D03*
Y-258646D02*
D03*
Y-236993D02*
D03*
X332932Y-217308D02*
D03*
Y-207465D02*
D03*
X348876Y-211402D02*
D03*
Y-219276D02*
D03*
Y-223213D02*
D03*
Y-238961D02*
D03*
X332932Y-203528D02*
D03*
X348876Y-229119D02*
D03*
Y-233056D02*
D03*
X332932Y-209434D02*
D03*
X348876Y-248804D02*
D03*
Y-246835D02*
D03*
X332932Y-252741D02*
D03*
Y-258646D02*
D03*
Y-223213D02*
D03*
Y-221245D02*
D03*
X348876Y-260615D02*
D03*
X332932Y-268489D02*
D03*
X348876Y-270457D02*
D03*
X332932Y-246835D02*
D03*
Y-260615D02*
D03*
Y-250772D02*
D03*
Y-248804D02*
D03*
Y-242898D02*
D03*
Y-231087D02*
D03*
Y-236993D02*
D03*
Y-266520D02*
D03*
Y-256678D02*
D03*
Y-262583D02*
D03*
Y-229119D02*
D03*
X348876Y-268489D02*
D03*
X332932Y-270457D02*
D03*
Y-240930D02*
D03*
Y-227150D02*
D03*
X348876Y-266520D02*
D03*
Y-272426D02*
D03*
Y-262583D02*
D03*
X332932Y-272426D02*
D03*
X348876Y-256678D02*
D03*
X332932Y-233056D02*
D03*
Y-238961D02*
D03*
X348876Y-252741D02*
D03*
X332932Y-199591D02*
D03*
X348876D02*
D03*
Y-264552D02*
D03*
Y-254709D02*
D03*
Y-244867D02*
D03*
Y-235024D02*
D03*
Y-225182D02*
D03*
Y-215339D02*
D03*
Y-205497D02*
D03*
X332932Y-264552D02*
D03*
Y-254709D02*
D03*
Y-244867D02*
D03*
Y-235024D02*
D03*
Y-225182D02*
D03*
Y-215339D02*
D03*
Y-205497D02*
D03*
Y-195654D02*
D03*
X348876D02*
D03*
Y-197623D02*
D03*
Y-250772D02*
D03*
X332932Y-197623D02*
D03*
X520423Y-227160D02*
D03*
Y-225192D02*
D03*
Y-250782D02*
D03*
Y-266530D02*
D03*
Y-254719D02*
D03*
Y-246845D02*
D03*
Y-258656D02*
D03*
Y-237003D02*
D03*
Y-240940D02*
D03*
X536367Y-256688D02*
D03*
Y-248814D02*
D03*
Y-254719D02*
D03*
Y-266530D02*
D03*
X520423Y-264562D02*
D03*
Y-260625D02*
D03*
Y-209444D02*
D03*
Y-231097D02*
D03*
X536367Y-250782D02*
D03*
Y-260625D02*
D03*
X520423Y-256688D02*
D03*
Y-248814D02*
D03*
Y-244877D02*
D03*
Y-229129D02*
D03*
X536367Y-264562D02*
D03*
X520423Y-238971D02*
D03*
Y-235034D02*
D03*
X536367Y-258656D02*
D03*
X520423Y-219286D02*
D03*
Y-221255D02*
D03*
X536367Y-215349D02*
D03*
Y-209444D02*
D03*
Y-244877D02*
D03*
Y-246845D02*
D03*
X520423Y-207475D02*
D03*
X536367Y-199601D02*
D03*
X520423Y-197633D02*
D03*
X536367Y-221255D02*
D03*
Y-207475D02*
D03*
Y-217318D02*
D03*
Y-219286D02*
D03*
Y-225192D02*
D03*
Y-237003D02*
D03*
Y-231097D02*
D03*
Y-201570D02*
D03*
Y-211412D02*
D03*
Y-205507D02*
D03*
Y-238971D02*
D03*
X520423Y-199601D02*
D03*
X536367Y-197633D02*
D03*
Y-227160D02*
D03*
Y-240940D02*
D03*
X520423Y-201570D02*
D03*
Y-195664D02*
D03*
Y-205507D02*
D03*
X536367Y-195664D02*
D03*
X520423Y-211412D02*
D03*
X536367Y-235034D02*
D03*
Y-229129D02*
D03*
X520423Y-215349D02*
D03*
X536367Y-268499D02*
D03*
X520423D02*
D03*
Y-203538D02*
D03*
Y-213381D02*
D03*
Y-223223D02*
D03*
Y-233066D02*
D03*
Y-242908D02*
D03*
Y-252751D02*
D03*
Y-262593D02*
D03*
X536367Y-203538D02*
D03*
Y-213381D02*
D03*
Y-223223D02*
D03*
Y-233066D02*
D03*
Y-242908D02*
D03*
Y-252751D02*
D03*
Y-262593D02*
D03*
Y-272436D02*
D03*
X520423D02*
D03*
Y-270467D02*
D03*
Y-217318D02*
D03*
X536367Y-270467D02*
D03*
D185*
X293445Y-245593D02*
D03*
X309193D02*
D03*
X293445Y-243593D02*
D03*
X309193D02*
D03*
X293445Y-241593D02*
D03*
X309193D02*
D03*
X293445Y-239593D02*
D03*
X309193D02*
D03*
X293445Y-237593D02*
D03*
X309193D02*
D03*
X293445Y-235593D02*
D03*
X309193D02*
D03*
X293445Y-233593D02*
D03*
X309193D02*
D03*
X293445Y-231593D02*
D03*
X309193D02*
D03*
X293445Y-229593D02*
D03*
X309193D02*
D03*
Y-227593D02*
D03*
X293445D02*
D03*
Y-245593D02*
D03*
X309193D02*
D03*
X293445Y-243593D02*
D03*
X309193D02*
D03*
X293445Y-241593D02*
D03*
X309193D02*
D03*
X293445Y-239593D02*
D03*
X309193D02*
D03*
X293445Y-237593D02*
D03*
X309193D02*
D03*
X293445Y-235593D02*
D03*
X309193D02*
D03*
X293445Y-233593D02*
D03*
X309193D02*
D03*
X293445Y-231593D02*
D03*
X309193D02*
D03*
X293445Y-229593D02*
D03*
X309193D02*
D03*
Y-227593D02*
D03*
X293445D02*
D03*
D186*
X371107Y-112598D02*
D03*
X359493D02*
D03*
Y-136221D02*
D03*
X371107D02*
D03*
X601083Y-167717D02*
D03*
X589468D02*
D03*
X359493Y-124803D02*
D03*
X371107D02*
D03*
D187*
X609291Y-316535D02*
D03*
Y-343543D02*
D03*
X599291Y-316535D02*
D03*
Y-343543D02*
D03*
X589291Y-316535D02*
D03*
Y-343543D02*
D03*
X579291Y-316535D02*
D03*
Y-343543D02*
D03*
X569291Y-316535D02*
D03*
Y-343543D02*
D03*
D188*
X540493Y-331738D02*
D03*
X532619D02*
D03*
X540099Y-347880D02*
D03*
X532225D02*
D03*
D189*
X655118Y-346457D02*
D03*
Y-338583D02*
D03*
X637008Y-346850D02*
D03*
Y-338976D02*
D03*
D190*
X515198Y-329179D02*
D03*
Y-334297D02*
D03*
X524056Y-331738D02*
D03*
X515099Y-345321D02*
D03*
Y-350439D02*
D03*
X523958Y-347880D02*
D03*
D191*
X639567Y-320374D02*
D03*
X634449D02*
D03*
X637008Y-329232D02*
D03*
X658268Y-320473D02*
D03*
X653150D02*
D03*
X655709Y-329331D02*
D03*
D192*
X577559Y-117323D02*
D03*
Y-124409D02*
D03*
X357480Y-96850D02*
D03*
Y-103937D02*
D03*
D193*
X81988Y-215551D02*
D03*
Y-213583D02*
D03*
Y-211614D02*
D03*
Y-209646D02*
D03*
X69587D02*
D03*
Y-211614D02*
D03*
Y-213583D02*
D03*
Y-215551D02*
D03*
X81004Y-162402D02*
D03*
Y-160433D02*
D03*
Y-158465D02*
D03*
Y-156496D02*
D03*
X68602D02*
D03*
Y-158465D02*
D03*
Y-160433D02*
D03*
Y-162402D02*
D03*
X81988Y-267717D02*
D03*
Y-265748D02*
D03*
Y-263779D02*
D03*
Y-261811D02*
D03*
X69587D02*
D03*
Y-263779D02*
D03*
Y-265748D02*
D03*
Y-267717D02*
D03*
X81004Y-321850D02*
D03*
Y-319882D02*
D03*
Y-317913D02*
D03*
Y-315945D02*
D03*
X68602D02*
D03*
Y-317913D02*
D03*
Y-319882D02*
D03*
Y-321850D02*
D03*
D194*
X47244Y-4626D02*
D03*
Y689D02*
D03*
X40354Y-4626D02*
D03*
Y689D02*
D03*
X33465Y-4626D02*
D03*
Y689D02*
D03*
X26575Y-4626D02*
D03*
Y689D02*
D03*
X199803Y-119439D02*
D03*
Y-114517D02*
D03*
D195*
X94193Y-120079D02*
D03*
Y-122047D02*
D03*
Y-124016D02*
D03*
Y-125984D02*
D03*
Y-127953D02*
D03*
Y-129921D02*
D03*
Y-131890D02*
D03*
X112500D02*
D03*
Y-129921D02*
D03*
Y-127953D02*
D03*
Y-125984D02*
D03*
Y-124016D02*
D03*
Y-122047D02*
D03*
Y-120079D02*
D03*
D196*
X97441Y-135138D02*
D03*
X99410D02*
D03*
X101378D02*
D03*
X103347D02*
D03*
X105315D02*
D03*
X107283D02*
D03*
X109252D02*
D03*
X109252Y-116831D02*
D03*
X107283D02*
D03*
X105315D02*
D03*
X103347D02*
D03*
X101378D02*
D03*
X99410D02*
D03*
X97441D02*
D03*
D197*
X103347Y-125984D02*
D03*
D198*
X-18406Y-187795D02*
D03*
Y-176772D02*
D03*
Y-240551D02*
D03*
Y-229528D02*
D03*
Y-294094D02*
D03*
Y-283071D02*
D03*
Y-346850D02*
D03*
Y-335827D02*
D03*
Y-113976D02*
D03*
Y-102953D02*
D03*
Y-70669D02*
D03*
Y-59646D02*
D03*
D199*
X-19685Y-184055D02*
D03*
Y-180512D02*
D03*
Y-236811D02*
D03*
Y-233268D02*
D03*
Y-290354D02*
D03*
Y-286811D02*
D03*
Y-343110D02*
D03*
Y-339567D02*
D03*
Y-110236D02*
D03*
Y-106693D02*
D03*
Y-66929D02*
D03*
Y-63386D02*
D03*
D200*
X44291Y-256988D02*
D03*
Y-268602D02*
D03*
Y-151673D02*
D03*
Y-163287D02*
D03*
Y-311122D02*
D03*
Y-322736D02*
D03*
Y-204823D02*
D03*
Y-216437D02*
D03*
D201*
X38287Y-262795D02*
D03*
Y-157480D02*
D03*
Y-316929D02*
D03*
Y-210630D02*
D03*
D202*
X74803Y-335630D02*
D03*
Y-329724D02*
D03*
X82677Y-335630D02*
D03*
Y-329724D02*
D03*
X75787Y-227362D02*
D03*
Y-221457D02*
D03*
X82677Y-227362D02*
D03*
Y-221457D02*
D03*
X83661Y-281496D02*
D03*
Y-275590D02*
D03*
X75787Y-281496D02*
D03*
Y-275590D02*
D03*
X74803Y-175197D02*
D03*
Y-169291D02*
D03*
X82677Y-175197D02*
D03*
Y-169291D02*
D03*
D203*
X59646Y-316929D02*
D03*
X54134D02*
D03*
X60827Y-210630D02*
D03*
X55315D02*
D03*
X60827Y-262795D02*
D03*
X55315D02*
D03*
X54331Y-157480D02*
D03*
X59842D02*
D03*
D204*
X460925Y-137647D02*
D03*
X456398D02*
D03*
D205*
X31496Y-184055D02*
D03*
Y-291732D02*
D03*
D206*
X38189Y-184055D02*
D03*
Y-175394D02*
D03*
X30709D02*
D03*
X38189Y-291732D02*
D03*
Y-283071D02*
D03*
X30709D02*
D03*
D207*
X281102Y-401427D02*
D03*
X159055D02*
D03*
X155118D02*
D03*
X151181D02*
D03*
X178740D02*
D03*
X222047D02*
D03*
X265354D02*
D03*
X261417D02*
D03*
X249606D02*
D03*
X245669D02*
D03*
X233858D02*
D03*
X229921D02*
D03*
X214173D02*
D03*
X210236D02*
D03*
X186614D02*
D03*
X182677D02*
D03*
X202362D02*
D03*
X273228D02*
D03*
X166929D02*
D03*
X170866D02*
D03*
X190551D02*
D03*
X269291D02*
D03*
X257480D02*
D03*
X241732D02*
D03*
X237795D02*
D03*
X174803D02*
D03*
X162992D02*
D03*
X253543D02*
D03*
X206299D02*
D03*
X218110D02*
D03*
X225984D02*
D03*
D208*
X277165Y-399477D02*
D03*
D209*
X279528Y-113946D02*
D03*
Y-118947D02*
D03*
Y-123946D02*
D03*
Y-128946D02*
D03*
X298425Y-113946D02*
D03*
Y-118947D02*
D03*
Y-123946D02*
D03*
Y-128946D02*
D03*
D210*
X209252Y-114399D02*
D03*
Y-119399D02*
D03*
Y-124399D02*
D03*
Y-129399D02*
D03*
X227756Y-114399D02*
D03*
Y-119399D02*
D03*
Y-124399D02*
D03*
Y-129399D02*
D03*
D211*
X597598Y-159449D02*
D03*
X592165D02*
D03*
X110709Y-263632D02*
D03*
X116142D02*
D03*
D212*
X695866Y-105610D02*
D03*
Y-72342D02*
D03*
X688976D02*
D03*
Y-105610D02*
D03*
D213*
X682283Y-74803D02*
D03*
Y-103150D02*
D03*
D214*
X672401Y-135695D02*
D03*
D215*
X643701Y-127445D02*
D03*
D216*
Y-143945D02*
D03*
X622001Y-127445D02*
D03*
Y-143945D02*
D03*
D217*
X640640Y-65206D02*
D03*
Y-17962D02*
D03*
X82785Y-22490D02*
D03*
Y-69734D02*
D03*
X640640Y-33710D02*
D03*
Y-17962D02*
D03*
X82785Y-53986D02*
D03*
Y-69734D02*
D03*
D218*
X181496Y-120079D02*
D03*
D219*
X171496D02*
D03*
X161496D02*
D03*
X151496D02*
D03*
X141496D02*
D03*
D220*
X270472Y-327165D02*
D03*
X282283D02*
D03*
X142520Y-156693D02*
D03*
X294094Y-327165D02*
D03*
X142520Y-316535D02*
D03*
X302362Y-156693D02*
D03*
X142520Y-236614D02*
D03*
X258472Y-327165D02*
D03*
X302362Y-316535D02*
D03*
X246472Y-327165D02*
D03*
X258472D02*
D03*
X282283D02*
D03*
X294094D02*
D03*
X302362Y-156693D02*
D03*
Y-316535D02*
D03*
X142520D02*
D03*
Y-236614D02*
D03*
Y-156693D02*
D03*
X270472Y-327165D02*
D03*
X246472D02*
D03*
D221*
X470275Y-308597D02*
D03*
X391535D02*
D03*
X340904Y-273410D02*
D03*
Y-194670D02*
D03*
X391545Y-160477D02*
D03*
X470285D02*
D03*
X528395Y-194680D02*
D03*
Y-273420D02*
D03*
D222*
X285128Y-308632D02*
D03*
X160020Y-314535D02*
D03*
X162520Y-152693D02*
D03*
X284862Y-164793D02*
D03*
D223*
X533015Y-312764D02*
D03*
X336415Y-155764D02*
D03*
X336515Y-312764D02*
D03*
X533015Y-155764D02*
D03*
D224*
X604291Y-330039D02*
D03*
X574291D02*
D03*
D225*
X-18464Y-326781D02*
D03*
X1535D02*
D03*
Y-306781D02*
D03*
X-18464D02*
D03*
X-18465Y-273630D02*
D03*
X1535D02*
D03*
Y-253630D02*
D03*
X-18465D02*
D03*
Y-220480D02*
D03*
X1535D02*
D03*
Y-200480D02*
D03*
X-18465D02*
D03*
X-18464Y-167332D02*
D03*
X1535D02*
D03*
Y-147332D02*
D03*
X-18464D02*
D03*
D226*
X-8465Y-316781D02*
D03*
X-8465Y-263630D02*
D03*
Y-210480D02*
D03*
X-8465Y-157332D02*
D03*
D227*
X589055Y13937D02*
D03*
D228*
X579055D02*
D03*
X569055D02*
D03*
X559055D02*
D03*
X549055D02*
D03*
X539055D02*
D03*
X589055Y3937D02*
D03*
X579055D02*
D03*
X569055D02*
D03*
X559055D02*
D03*
X549055D02*
D03*
X539055D02*
D03*
D229*
X0Y0D02*
D03*
X0Y-378395D02*
D03*
X685039Y-340551D02*
D03*
X685039Y0D02*
D03*
X486221Y-340551D02*
D03*
D230*
X670538Y-74409D02*
D03*
X668438D02*
D03*
X676772Y-54331D02*
D03*
Y-51575D02*
D03*
X84079Y-105653D02*
D03*
X62986Y-112803D02*
D03*
X62499Y-117255D02*
D03*
X141981Y-347043D02*
D03*
X142520Y-342913D02*
D03*
X198392Y-366842D02*
D03*
X196701Y-370523D02*
D03*
X680709Y-216929D02*
D03*
X671654Y-217323D02*
D03*
X585433Y-114961D02*
D03*
X584252Y-117717D02*
D03*
X679921Y-160236D02*
D03*
X684646Y-161811D02*
D03*
X689370Y-161417D02*
D03*
X689764Y-164567D02*
D03*
Y-168110D02*
D03*
X476945Y-173228D02*
D03*
X555512Y-218504D02*
D03*
X474016Y-176378D02*
D03*
X460186Y-175448D02*
D03*
X578168Y-80778D02*
D03*
X530027Y-172987D02*
D03*
X533044Y-176225D02*
D03*
X495669Y-222047D02*
D03*
X500394Y-222835D02*
D03*
X644488Y-170472D02*
D03*
X644619Y-166285D02*
D03*
X644569Y-162910D02*
D03*
X644488Y-159843D02*
D03*
X435827Y-103543D02*
D03*
X402719Y-112334D02*
D03*
X409900Y-136559D02*
D03*
X430492Y-136473D02*
D03*
X414567Y-137402D02*
D03*
X436614Y-136614D02*
D03*
X443307Y-111024D02*
D03*
X664966Y-316582D02*
D03*
X664961Y-325984D02*
D03*
X692037Y-315878D02*
D03*
X692126Y-322441D02*
D03*
X256897Y-112001D02*
D03*
X255118Y-118504D02*
D03*
X254376Y-125747D02*
D03*
X241250Y-126247D02*
D03*
X238189Y-116142D02*
D03*
X246063Y-111024D02*
D03*
X248425Y-129134D02*
D03*
X241077Y-118805D02*
D03*
X255512Y-121260D02*
D03*
X253713Y-109190D02*
D03*
X253690Y-111960D02*
D03*
X244664Y-106952D02*
D03*
X228824Y-104850D02*
D03*
X577953Y-83858D02*
D03*
X618898Y-82284D02*
D03*
X612205Y-87008D02*
D03*
X609055Y-92520D02*
D03*
X620959Y-100047D02*
D03*
X612598Y-100000D02*
D03*
X629134Y-102756D02*
D03*
X631814Y-83784D02*
D03*
X629101Y-90137D02*
D03*
X623228Y-93307D02*
D03*
X616535Y-84646D02*
D03*
X616929Y-100000D02*
D03*
X599279Y-82981D02*
D03*
X597227Y-77103D02*
D03*
X601745Y-98051D02*
D03*
X588372Y-100945D02*
D03*
X567323Y-94095D02*
D03*
X569291Y-91339D02*
D03*
X568504Y-88189D02*
D03*
X579921Y-101969D02*
D03*
X584763Y-100116D02*
D03*
X588976Y-86221D02*
D03*
X600394Y-87795D02*
D03*
X592520Y-93307D02*
D03*
X666929Y-98032D02*
D03*
X662539Y-107066D02*
D03*
X667717Y-106693D02*
D03*
X696762Y-63288D02*
D03*
X696577Y-51453D02*
D03*
X675591Y-42520D02*
D03*
X685716Y-22157D02*
D03*
X679517Y-26553D02*
D03*
Y-37023D02*
D03*
X693915Y-33393D02*
D03*
X686728Y-33442D02*
D03*
X686319Y-43553D02*
D03*
X683127Y-66209D02*
D03*
X689466Y-66165D02*
D03*
X680082Y-64183D02*
D03*
X675926Y-72691D02*
D03*
X660719Y-75726D02*
D03*
X694095Y-62205D02*
D03*
X693977Y-53201D02*
D03*
X676378Y-83858D02*
D03*
X538583Y-111811D02*
D03*
X539233Y-115729D02*
D03*
X569092Y-108048D02*
D03*
X546386Y-109024D02*
D03*
X548093Y-185219D02*
D03*
X548425Y-181890D02*
D03*
X548819Y-178740D02*
D03*
X547244Y-157087D02*
D03*
Y-144488D02*
D03*
X524409Y-135827D02*
D03*
X531801Y-127495D02*
D03*
X539900Y-140766D02*
D03*
X570472Y-137795D02*
D03*
X579921Y-133465D02*
D03*
X574409D02*
D03*
X570866D02*
D03*
X572047Y-129921D02*
D03*
X576378D02*
D03*
X580315D02*
D03*
X646457Y-156693D02*
D03*
X642520D02*
D03*
X635039Y-216142D02*
D03*
X608661Y-236221D02*
D03*
X572441Y-227165D02*
D03*
X678441Y-292586D02*
D03*
X678346Y-297244D02*
D03*
X639764Y-283858D02*
D03*
X554724Y-294882D02*
D03*
X565354Y-292913D02*
D03*
X630577Y-278001D02*
D03*
X582874Y-294291D02*
D03*
X680709Y-212205D02*
D03*
X673622Y-213779D02*
D03*
X669685D02*
D03*
X666142Y-212992D02*
D03*
X599564Y-178940D02*
D03*
X594882Y-179134D02*
D03*
X589764D02*
D03*
X584646Y-178740D02*
D03*
X635827Y-187795D02*
D03*
X635433Y-184252D02*
D03*
X652756Y-164961D02*
D03*
X657480Y-164567D02*
D03*
X662992Y-164961D02*
D03*
X668504D02*
D03*
X681496Y-179528D02*
D03*
X677165Y-172441D02*
D03*
X673228D02*
D03*
X675197Y-200000D02*
D03*
X678740D02*
D03*
X681890D02*
D03*
Y-196850D02*
D03*
X678740D02*
D03*
X675591Y-196457D02*
D03*
X652756Y-218504D02*
D03*
X650000Y-231102D02*
D03*
X646434Y-231245D02*
D03*
X598425Y-198819D02*
D03*
X595276D02*
D03*
X592126D02*
D03*
X589764D02*
D03*
X587008D02*
D03*
X570079Y-200000D02*
D03*
X549298Y-191988D02*
D03*
X600000Y-248425D02*
D03*
X616535Y-255512D02*
D03*
X612205Y-251575D02*
D03*
X624803Y-255906D02*
D03*
Y-251575D02*
D03*
X624409Y-248031D02*
D03*
X611417Y-247638D02*
D03*
X605118Y-244488D02*
D03*
X673228Y-251181D02*
D03*
X672835Y-257087D02*
D03*
X673622Y-261417D02*
D03*
X676378Y-266142D02*
D03*
X676772Y-270866D02*
D03*
X671260Y-274803D02*
D03*
Y-278740D02*
D03*
X671654Y-283071D02*
D03*
X683858Y-310630D02*
D03*
X683716Y-298538D02*
D03*
X651575Y-275197D02*
D03*
X648819Y-278740D02*
D03*
X652362Y-279528D02*
D03*
X657087D02*
D03*
X654331Y-283858D02*
D03*
X650000D02*
D03*
X646457D02*
D03*
X637795Y-297638D02*
D03*
X585039Y-249606D02*
D03*
X590551Y-266535D02*
D03*
X588189Y-263386D02*
D03*
X585433Y-253937D02*
D03*
Y-257480D02*
D03*
X581496D02*
D03*
X577953D02*
D03*
X559842Y-257087D02*
D03*
X579134Y-195276D02*
D03*
X574803D02*
D03*
X577953Y-198819D02*
D03*
X590158Y-226378D02*
D03*
X586221Y-226772D02*
D03*
X579921Y-227559D02*
D03*
X576772Y-228740D02*
D03*
X637008Y-238583D02*
D03*
X608661Y-242126D02*
D03*
X590551Y-242520D02*
D03*
X586537Y-234843D02*
D03*
X546850Y-213779D02*
D03*
X548819Y-196063D02*
D03*
X547244Y-203150D02*
D03*
X554724Y-207874D02*
D03*
X549213D02*
D03*
X569291Y-194095D02*
D03*
X581496Y-198819D02*
D03*
X573622D02*
D03*
X571162Y-284136D02*
D03*
X577953Y-284646D02*
D03*
X574803Y-284252D02*
D03*
X568110D02*
D03*
X567717Y-259055D02*
D03*
X566535Y-255906D02*
D03*
X570079D02*
D03*
X548425Y-253543D02*
D03*
X545669Y-253937D02*
D03*
X545128Y-280872D02*
D03*
X544909Y-287437D02*
D03*
X545276Y-294094D02*
D03*
Y-275197D02*
D03*
Y-270866D02*
D03*
X544488Y-265748D02*
D03*
X557087Y-261417D02*
D03*
X556628Y-258042D02*
D03*
X569548Y-287223D02*
D03*
X595276Y-291732D02*
D03*
X612598D02*
D03*
X627559Y-296457D02*
D03*
X563386Y-257874D02*
D03*
X572441Y-258268D02*
D03*
X475984Y-127165D02*
D03*
X480120Y-132365D02*
D03*
X469685Y-133465D02*
D03*
X473228Y-105905D02*
D03*
X488583Y-132283D02*
D03*
X506299Y-129921D02*
D03*
X498032Y-132283D02*
D03*
X506207Y-127333D02*
D03*
X505905Y-123622D02*
D03*
X472441Y-113779D02*
D03*
X483484Y-105840D02*
D03*
X504703Y-106672D02*
D03*
X508268Y-117323D02*
D03*
X501669Y-116601D02*
D03*
X500313Y-105734D02*
D03*
X476772Y-123622D02*
D03*
X518337Y-159634D02*
D03*
X515702Y-162803D02*
D03*
X498693Y-188351D02*
D03*
X498819Y-183858D02*
D03*
X499111Y-179528D02*
D03*
X658114Y-56714D02*
D03*
X657445Y-63525D02*
D03*
X658053Y-71188D02*
D03*
X623511Y-62552D02*
D03*
X623228Y-55118D02*
D03*
X423461Y-178869D02*
D03*
X144871Y-131609D02*
D03*
X314417Y-228033D02*
D03*
X314623Y-231391D02*
D03*
X416835Y-196581D02*
D03*
X411811Y-196850D02*
D03*
X314658Y-244775D02*
D03*
X315097Y-235081D02*
D03*
X314503Y-225180D02*
D03*
D231*
X348211Y-89891D02*
D03*
X357798Y-89963D02*
D03*
D232*
X651545Y-95108D02*
D03*
X413356Y7254D02*
D03*
Y-95108D02*
D03*
X651545Y7254D02*
D03*
X71880Y7412D02*
D03*
X310069Y-94950D02*
D03*
Y7412D02*
D03*
X71880Y-94950D02*
D03*
D233*
X99016Y-121653D02*
D03*
X103347D02*
D03*
X107677D02*
D03*
X99016Y-125984D02*
D03*
X103347D02*
D03*
X107677D02*
D03*
X99016Y-130315D02*
D03*
X103347D02*
D03*
X107677D02*
D03*
M02*
